(kicad_sch
	(version 20250114)
	(generator "eeschema")
	(generator_version "9.0")
	(paper "A3")
	(title_block
		(title "SO-DIMM DDR5 Tester")
		(date "2025-11-26")
		(rev "1.3.0")
		(company "Antmicro Ltd.")
		(comment 1 "www.antmicro.com")
		(comment 2 "Antmicro Ltd")
	)
	(text "HDMI"
		(exclude_from_sim no)
		(at 13.335 141.605 0)
		(effects
			(font
				(size 2.9972 2.9972)
				(thickness 0.5994)
				(bold yes)
			)
			(justify left bottom)
		)
	)
	(text "SD card"
		(exclude_from_sim no)
		(at 13.97 18.415 0)
		(effects
			(font
				(size 2.9972 2.9972)
				(thickness 0.5994)
				(bold yes)
			)
			(justify left bottom)
		)
	)
	(junction
		(at 252.73 196.85)
		(diameter 0)
		(color 0 0 0 0)
	)
	(junction
		(at 188.595 31.115)
		(diameter 0)
		(color 0 0 0 0)
	)
	(junction
		(at 207.645 31.115)
		(diameter 0)
		(color 0 0 0 0)
	)
	(junction
		(at 189.23 207.01)
		(diameter 0)
		(color 0 0 0 0)
	)
	(junction
		(at 226.695 31.115)
		(diameter 0)
		(color 0 0 0 0)
	)
	(junction
		(at 201.295 60.96)
		(diameter 0)
		(color 0 0 0 0)
	)
	(junction
		(at 269.24 212.09)
		(diameter 0)
		(color 0 0 0 0)
	)
	(junction
		(at 201.93 207.01)
		(diameter 0)
		(color 0 0 0 0)
	)
	(junction
		(at 252.73 199.39)
		(diameter 0)
		(color 0 0 0 0)
	)
	(junction
		(at 194.945 31.115)
		(diameter 0)
		(color 0 0 0 0)
	)
	(junction
		(at 220.345 31.115)
		(diameter 0)
		(color 0 0 0 0)
	)
	(junction
		(at 220.345 53.34)
		(diameter 0)
		(color 0 0 0 0)
	)
	(junction
		(at 188.595 66.04)
		(diameter 0)
		(color 0 0 0 0)
	)
	(junction
		(at 252.73 204.47)
		(diameter 0)
		(color 0 0 0 0)
	)
	(junction
		(at 226.695 50.8)
		(diameter 0)
		(color 0 0 0 0)
	)
	(junction
		(at 207.645 58.42)
		(diameter 0)
		(color 0 0 0 0)
	)
	(junction
		(at 194.945 63.5)
		(diameter 0)
		(color 0 0 0 0)
	)
	(junction
		(at 208.915 207.01)
		(diameter 0)
		(color 0 0 0 0)
	)
	(junction
		(at 213.995 55.88)
		(diameter 0)
		(color 0 0 0 0)
	)
	(junction
		(at 252.73 201.93)
		(diameter 0)
		(color 0 0 0 0)
	)
	(junction
		(at 201.295 31.115)
		(diameter 0)
		(color 0 0 0 0)
	)
	(junction
		(at 213.995 31.115)
		(diameter 0)
		(color 0 0 0 0)
	)
	(junction
		(at 257.81 212.09)
		(diameter 0)
		(color 0 0 0 0)
	)
	(junction
		(at 269.24 220.98)
		(diameter 0)
		(color 0 0 0 0)
	)
	(no_connect
		(at 226.06 201.93)
	)
	(no_connect
		(at 186.055 86.36)
	)
	(bus_entry
		(at 177.8 53.34)
		(size -2.54 -2.54)
		(stroke
			(width 0)
			(type default)
		)
	)
	(bus_entry
		(at 177.8 66.04)
		(size -2.54 -2.54)
		(stroke
			(width 0)
			(type default)
		)
	)
	(bus_entry
		(at 177.8 173.99)
		(size -2.54 -2.54)
		(stroke
			(width 0)
			(type default)
		)
	)
	(bus_entry
		(at 177.8 179.07)
		(size -2.54 -2.54)
		(stroke
			(width 0)
			(type default)
		)
	)
	(bus_entry
		(at 177.8 181.61)
		(size -2.54 -2.54)
		(stroke
			(width 0)
			(type default)
		)
	)
	(bus_entry
		(at 177.8 50.8)
		(size -2.54 -2.54)
		(stroke
			(width 0)
			(type default)
		)
	)
	(bus_entry
		(at 177.8 63.5)
		(size -2.54 -2.54)
		(stroke
			(width 0)
			(type default)
		)
	)
	(bus_entry
		(at 177.8 158.75)
		(size -2.54 -2.54)
		(stroke
			(width 0)
			(type default)
		)
	)
	(bus_entry
		(at 177.8 171.45)
		(size -2.54 -2.54)
		(stroke
			(width 0)
			(type default)
		)
	)
	(bus_entry
		(at 177.8 156.21)
		(size -2.54 -2.54)
		(stroke
			(width 0)
			(type default)
		)
	)
	(bus_entry
		(at 177.8 166.37)
		(size -2.54 -2.54)
		(stroke
			(width 0)
			(type default)
		)
	)
	(bus_entry
		(at 177.8 163.83)
		(size -2.54 -2.54)
		(stroke
			(width 0)
			(type default)
		)
	)
	(bus_entry
		(at 177.8 58.42)
		(size -2.54 -2.54)
		(stroke
			(width 0)
			(type default)
		)
	)
	(bus_entry
		(at 177.8 55.88)
		(size -2.54 -2.54)
		(stroke
			(width 0)
			(type default)
		)
	)
	(bus_entry
		(at 177.8 60.96)
		(size -2.54 -2.54)
		(stroke
			(width 0)
			(type default)
		)
	)
	(wire
		(pts
			(xy 208.915 207.01) (xy 208.915 210.82)
		)
		(stroke
			(width 0)
			(type default)
		)
	)
	(wire
		(pts
			(xy 193.04 158.75) (xy 177.8 158.75)
		)
		(stroke
			(width 0)
			(type default)
		)
	)
	(wire
		(pts
			(xy 195.58 241.935) (xy 195.58 243.205)
		)
		(stroke
			(width 0)
			(type default)
		)
	)
	(wire
		(pts
			(xy 188.595 29.845) (xy 188.595 31.115)
		)
		(stroke
			(width 0)
			(type default)
		)
	)
	(wire
		(pts
			(xy 233.045 45.72) (xy 234.95 45.72)
		)
		(stroke
			(width 0)
			(type default)
		)
	)
	(bus
		(pts
			(xy 175.26 171.45) (xy 175.26 176.53)
		)
		(stroke
			(width 0)
			(type default)
		)
	)
	(wire
		(pts
			(xy 198.12 156.21) (xy 226.06 156.21)
		)
		(stroke
			(width 0)
			(type default)
		)
	)
	(wire
		(pts
			(xy 226.695 50.8) (xy 234.95 50.8)
		)
		(stroke
			(width 0)
			(type default)
		)
	)
	(wire
		(pts
			(xy 251.46 199.39) (xy 252.73 199.39)
		)
		(stroke
			(width 0)
			(type default)
		)
	)
	(wire
		(pts
			(xy 251.46 201.93) (xy 252.73 201.93)
		)
		(stroke
			(width 0)
			(type default)
		)
	)
	(wire
		(pts
			(xy 193.04 171.45) (xy 177.8 171.45)
		)
		(stroke
			(width 0)
			(type default)
		)
	)
	(wire
		(pts
			(xy 201.295 36.195) (xy 201.295 31.115)
		)
		(stroke
			(width 0)
			(type default)
		)
	)
	(wire
		(pts
			(xy 188.595 66.04) (xy 210.185 66.04)
		)
		(stroke
			(width 0)
			(type default)
		)
	)
	(wire
		(pts
			(xy 188.595 41.275) (xy 188.595 66.04)
		)
		(stroke
			(width 0)
			(type default)
		)
	)
	(wire
		(pts
			(xy 207.645 41.275) (xy 207.645 58.42)
		)
		(stroke
			(width 0)
			(type default)
		)
	)
	(bus
		(pts
			(xy 175.26 152.4) (xy 175.26 153.67)
		)
		(stroke
			(width 0)
			(type default)
		)
	)
	(wire
		(pts
			(xy 177.8 55.88) (xy 213.995 55.88)
		)
		(stroke
			(width 0)
			(type default)
		)
	)
	(wire
		(pts
			(xy 252.73 196.85) (xy 252.73 199.39)
		)
		(stroke
			(width 0)
			(type default)
		)
	)
	(wire
		(pts
			(xy 193.04 181.61) (xy 177.8 181.61)
		)
		(stroke
			(width 0)
			(type default)
		)
	)
	(wire
		(pts
			(xy 198.12 179.07) (xy 226.06 179.07)
		)
		(stroke
			(width 0)
			(type default)
		)
	)
	(bus
		(pts
			(xy 175.26 48.26) (xy 175.26 50.8)
		)
		(stroke
			(width 0)
			(type default)
		)
	)
	(bus
		(pts
			(xy 175.26 55.88) (xy 175.26 58.42)
		)
		(stroke
			(width 0)
			(type default)
		)
	)
	(wire
		(pts
			(xy 177.165 36.83) (xy 177.165 38.1)
		)
		(stroke
			(width 0)
			(type default)
		)
	)
	(wire
		(pts
			(xy 177.8 106.68) (xy 186.055 106.68)
		)
		(stroke
			(width 0)
			(type default)
		)
	)
	(wire
		(pts
			(xy 213.995 55.88) (xy 234.95 55.88)
		)
		(stroke
			(width 0)
			(type default)
		)
	)
	(bus
		(pts
			(xy 175.26 168.91) (xy 175.26 171.45)
		)
		(stroke
			(width 0)
			(type default)
		)
	)
	(bus
		(pts
			(xy 175.26 58.42) (xy 175.26 60.96)
		)
		(stroke
			(width 0)
			(type default)
		)
	)
	(wire
		(pts
			(xy 201.295 41.275) (xy 201.295 60.96)
		)
		(stroke
			(width 0)
			(type default)
		)
	)
	(wire
		(pts
			(xy 207.645 58.42) (xy 234.95 58.42)
		)
		(stroke
			(width 0)
			(type default)
		)
	)
	(wire
		(pts
			(xy 198.12 181.61) (xy 226.06 181.61)
		)
		(stroke
			(width 0)
			(type default)
		)
	)
	(wire
		(pts
			(xy 186.055 111.76) (xy 184.785 111.76)
		)
		(stroke
			(width 0)
			(type default)
		)
	)
	(wire
		(pts
			(xy 234.95 66.04) (xy 215.265 66.04)
		)
		(stroke
			(width 0)
			(type default)
		)
	)
	(wire
		(pts
			(xy 177.8 262.89) (xy 196.85 262.89)
		)
		(stroke
			(width 0)
			(type default)
		)
	)
	(wire
		(pts
			(xy 196.85 265.43) (xy 195.58 265.43)
		)
		(stroke
			(width 0)
			(type default)
		)
	)
	(wire
		(pts
			(xy 177.8 60.96) (xy 201.295 60.96)
		)
		(stroke
			(width 0)
			(type default)
		)
	)
	(wire
		(pts
			(xy 177.8 104.14) (xy 186.055 104.14)
		)
		(stroke
			(width 0)
			(type default)
		)
	)
	(wire
		(pts
			(xy 251.46 194.31) (xy 252.73 194.31)
		)
		(stroke
			(width 0)
			(type default)
		)
	)
	(wire
		(pts
			(xy 213.995 41.275) (xy 213.995 55.88)
		)
		(stroke
			(width 0)
			(type default)
		)
	)
	(wire
		(pts
			(xy 198.12 207.01) (xy 201.93 207.01)
		)
		(stroke
			(width 0)
			(type default)
		)
	)
	(wire
		(pts
			(xy 201.93 206.375) (xy 201.93 207.01)
		)
		(stroke
			(width 0)
			(type default)
		)
	)
	(wire
		(pts
			(xy 193.04 179.07) (xy 177.8 179.07)
		)
		(stroke
			(width 0)
			(type default)
		)
	)
	(wire
		(pts
			(xy 177.8 81.28) (xy 186.055 81.28)
		)
		(stroke
			(width 0)
			(type default)
		)
	)
	(wire
		(pts
			(xy 220.345 36.195) (xy 220.345 31.115)
		)
		(stroke
			(width 0)
			(type default)
		)
	)
	(bus
		(pts
			(xy 175.26 163.83) (xy 175.26 168.91)
		)
		(stroke
			(width 0)
			(type default)
		)
	)
	(wire
		(pts
			(xy 177.8 236.855) (xy 196.85 236.855)
		)
		(stroke
			(width 0)
			(type default)
		)
	)
	(wire
		(pts
			(xy 177.8 255.27) (xy 196.85 255.27)
		)
		(stroke
			(width 0)
			(type default)
		)
	)
	(wire
		(pts
			(xy 213.995 36.195) (xy 213.995 31.115)
		)
		(stroke
			(width 0)
			(type default)
		)
	)
	(wire
		(pts
			(xy 193.04 166.37) (xy 177.8 166.37)
		)
		(stroke
			(width 0)
			(type default)
		)
	)
	(polyline
		(pts
			(xy 12.065 135.255) (xy 407.67 135.255)
		)
		(stroke
			(width 0)
			(type default)
		)
	)
	(wire
		(pts
			(xy 198.12 173.99) (xy 226.06 173.99)
		)
		(stroke
			(width 0)
			(type default)
		)
	)
	(wire
		(pts
			(xy 167.64 201.93) (xy 167.64 207.01)
		)
		(stroke
			(width 0)
			(type default)
		)
	)
	(wire
		(pts
			(xy 234.315 72.39) (xy 234.95 72.39)
		)
		(stroke
			(width 0)
			(type default)
		)
	)
	(bus
		(pts
			(xy 172.72 46.355) (xy 174.625 46.355)
		)
		(stroke
			(width 0)
			(type default)
		)
	)
	(wire
		(pts
			(xy 195.58 265.43) (xy 195.58 266.7)
		)
		(stroke
			(width 0)
			(type default)
		)
	)
	(wire
		(pts
			(xy 251.46 196.85) (xy 252.73 196.85)
		)
		(stroke
			(width 0)
			(type default)
		)
	)
	(wire
		(pts
			(xy 257.81 212.09) (xy 260.985 212.09)
		)
		(stroke
			(width 0)
			(type default)
		)
	)
	(bus
		(pts
			(xy 175.26 156.21) (xy 175.26 161.29)
		)
		(stroke
			(width 0)
			(type default)
		)
	)
	(wire
		(pts
			(xy 177.8 260.35) (xy 196.85 260.35)
		)
		(stroke
			(width 0)
			(type default)
		)
	)
	(wire
		(pts
			(xy 269.24 204.47) (xy 269.24 212.09)
		)
		(stroke
			(width 0)
			(type default)
		)
	)
	(wire
		(pts
			(xy 188.595 31.115) (xy 194.945 31.115)
		)
		(stroke
			(width 0)
			(type default)
		)
	)
	(wire
		(pts
			(xy 226.695 41.275) (xy 226.695 50.8)
		)
		(stroke
			(width 0)
			(type default)
		)
	)
	(wire
		(pts
			(xy 251.46 204.47) (xy 252.73 204.47)
		)
		(stroke
			(width 0)
			(type default)
		)
	)
	(wire
		(pts
			(xy 201.295 60.96) (xy 234.95 60.96)
		)
		(stroke
			(width 0)
			(type default)
		)
	)
	(wire
		(pts
			(xy 198.12 171.45) (xy 226.06 171.45)
		)
		(stroke
			(width 0)
			(type default)
		)
	)
	(wire
		(pts
			(xy 198.12 158.75) (xy 226.06 158.75)
		)
		(stroke
			(width 0)
			(type default)
		)
	)
	(wire
		(pts
			(xy 177.8 78.74) (xy 186.055 78.74)
		)
		(stroke
			(width 0)
			(type default)
		)
	)
	(wire
		(pts
			(xy 177.165 31.75) (xy 177.165 30.48)
		)
		(stroke
			(width 0)
			(type default)
		)
	)
	(wire
		(pts
			(xy 260.985 220.98) (xy 257.81 220.98)
		)
		(stroke
			(width 0)
			(type default)
		)
	)
	(wire
		(pts
			(xy 188.595 31.115) (xy 188.595 36.195)
		)
		(stroke
			(width 0)
			(type default)
		)
	)
	(wire
		(pts
			(xy 207.645 36.195) (xy 207.645 31.115)
		)
		(stroke
			(width 0)
			(type default)
		)
	)
	(wire
		(pts
			(xy 177.8 231.775) (xy 196.85 231.775)
		)
		(stroke
			(width 0)
			(type default)
		)
	)
	(bus
		(pts
			(xy 175.26 176.53) (xy 175.26 179.07)
		)
		(stroke
			(width 0)
			(type default)
		)
	)
	(wire
		(pts
			(xy 175.26 207.01) (xy 189.23 207.01)
		)
		(stroke
			(width 0)
			(type default)
		)
	)
	(wire
		(pts
			(xy 269.24 220.98) (xy 266.065 220.98)
		)
		(stroke
			(width 0)
			(type default)
		)
	)
	(wire
		(pts
			(xy 177.8 257.81) (xy 196.85 257.81)
		)
		(stroke
			(width 0)
			(type default)
		)
	)
	(wire
		(pts
			(xy 269.24 220.98) (xy 269.24 223.52)
		)
		(stroke
			(width 0)
			(type default)
		)
	)
	(wire
		(pts
			(xy 257.81 207.01) (xy 257.81 212.09)
		)
		(stroke
			(width 0)
			(type default)
		)
	)
	(wire
		(pts
			(xy 277.495 72.39) (xy 275.59 72.39)
		)
		(stroke
			(width 0)
			(type default)
		)
	)
	(wire
		(pts
			(xy 201.93 207.01) (xy 208.915 207.01)
		)
		(stroke
			(width 0)
			(type default)
		)
	)
	(wire
		(pts
			(xy 177.8 50.8) (xy 226.695 50.8)
		)
		(stroke
			(width 0)
			(type default)
		)
	)
	(wire
		(pts
			(xy 194.945 36.195) (xy 194.945 31.115)
		)
		(stroke
			(width 0)
			(type default)
		)
	)
	(wire
		(pts
			(xy 177.8 83.82) (xy 186.055 83.82)
		)
		(stroke
			(width 0)
			(type default)
		)
	)
	(wire
		(pts
			(xy 269.24 204.47) (xy 252.73 204.47)
		)
		(stroke
			(width 0)
			(type default)
		)
	)
	(wire
		(pts
			(xy 167.64 207.01) (xy 170.18 207.01)
		)
		(stroke
			(width 0)
			(type default)
		)
	)
	(wire
		(pts
			(xy 257.81 220.98) (xy 257.81 212.09)
		)
		(stroke
			(width 0)
			(type default)
		)
	)
	(wire
		(pts
			(xy 193.04 163.83) (xy 177.8 163.83)
		)
		(stroke
			(width 0)
			(type default)
		)
	)
	(wire
		(pts
			(xy 225.425 186.69) (xy 226.06 186.69)
		)
		(stroke
			(width 0)
			(type default)
		)
	)
	(wire
		(pts
			(xy 269.24 212.09) (xy 266.065 212.09)
		)
		(stroke
			(width 0)
			(type default)
		)
	)
	(wire
		(pts
			(xy 277.495 74.295) (xy 277.495 72.39)
		)
		(stroke
			(width 0)
			(type default)
		)
	)
	(wire
		(pts
			(xy 207.645 31.115) (xy 213.995 31.115)
		)
		(stroke
			(width 0)
			(type default)
		)
	)
	(bus
		(pts
			(xy 174.625 151.765) (xy 175.26 152.4)
		)
		(stroke
			(width 0)
			(type default)
		)
	)
	(wire
		(pts
			(xy 177.8 66.04) (xy 188.595 66.04)
		)
		(stroke
			(width 0)
			(type default)
		)
	)
	(wire
		(pts
			(xy 193.04 156.21) (xy 177.8 156.21)
		)
		(stroke
			(width 0)
			(type default)
		)
	)
	(wire
		(pts
			(xy 225.425 194.31) (xy 226.06 194.31)
		)
		(stroke
			(width 0)
			(type default)
		)
	)
	(wire
		(pts
			(xy 186.055 88.9) (xy 184.785 88.9)
		)
		(stroke
			(width 0)
			(type default)
		)
	)
	(wire
		(pts
			(xy 252.73 199.39) (xy 252.73 201.93)
		)
		(stroke
			(width 0)
			(type default)
		)
	)
	(wire
		(pts
			(xy 193.04 173.99) (xy 177.8 173.99)
		)
		(stroke
			(width 0)
			(type default)
		)
	)
	(wire
		(pts
			(xy 213.995 31.115) (xy 220.345 31.115)
		)
		(stroke
			(width 0)
			(type default)
		)
	)
	(wire
		(pts
			(xy 177.8 239.395) (xy 196.85 239.395)
		)
		(stroke
			(width 0)
			(type default)
		)
	)
	(wire
		(pts
			(xy 201.295 31.115) (xy 207.645 31.115)
		)
		(stroke
			(width 0)
			(type default)
		)
	)
	(wire
		(pts
			(xy 220.345 31.115) (xy 226.695 31.115)
		)
		(stroke
			(width 0)
			(type default)
		)
	)
	(wire
		(pts
			(xy 194.945 41.275) (xy 194.945 63.5)
		)
		(stroke
			(width 0)
			(type default)
		)
	)
	(bus
		(pts
			(xy 175.26 60.96) (xy 175.26 63.5)
		)
		(stroke
			(width 0)
			(type default)
		)
	)
	(wire
		(pts
			(xy 225.425 199.39) (xy 226.06 199.39)
		)
		(stroke
			(width 0)
			(type default)
		)
	)
	(bus
		(pts
			(xy 175.26 53.34) (xy 175.26 55.88)
		)
		(stroke
			(width 0)
			(type default)
		)
	)
	(wire
		(pts
			(xy 177.8 63.5) (xy 194.945 63.5)
		)
		(stroke
			(width 0)
			(type default)
		)
	)
	(wire
		(pts
			(xy 177.8 53.34) (xy 220.345 53.34)
		)
		(stroke
			(width 0)
			(type default)
		)
	)
	(wire
		(pts
			(xy 198.12 163.83) (xy 226.06 163.83)
		)
		(stroke
			(width 0)
			(type default)
		)
	)
	(wire
		(pts
			(xy 269.24 220.98) (xy 269.24 212.09)
		)
		(stroke
			(width 0)
			(type default)
		)
	)
	(wire
		(pts
			(xy 252.73 194.31) (xy 252.73 196.85)
		)
		(stroke
			(width 0)
			(type default)
		)
	)
	(wire
		(pts
			(xy 184.785 88.9) (xy 184.785 90.17)
		)
		(stroke
			(width 0)
			(type default)
		)
	)
	(wire
		(pts
			(xy 177.8 234.315) (xy 196.85 234.315)
		)
		(stroke
			(width 0)
			(type default)
		)
	)
	(wire
		(pts
			(xy 252.73 201.93) (xy 252.73 204.47)
		)
		(stroke
			(width 0)
			(type default)
		)
	)
	(wire
		(pts
			(xy 226.695 31.115) (xy 233.045 31.115)
		)
		(stroke
			(width 0)
			(type default)
		)
	)
	(wire
		(pts
			(xy 177.8 58.42) (xy 207.645 58.42)
		)
		(stroke
			(width 0)
			(type default)
		)
	)
	(wire
		(pts
			(xy 194.945 31.115) (xy 201.295 31.115)
		)
		(stroke
			(width 0)
			(type default)
		)
	)
	(wire
		(pts
			(xy 196.85 241.935) (xy 195.58 241.935)
		)
		(stroke
			(width 0)
			(type default)
		)
	)
	(wire
		(pts
			(xy 177.8 101.6) (xy 186.055 101.6)
		)
		(stroke
			(width 0)
			(type default)
		)
	)
	(wire
		(pts
			(xy 208.915 205.74) (xy 208.915 207.01)
		)
		(stroke
			(width 0)
			(type default)
		)
	)
	(wire
		(pts
			(xy 233.045 31.115) (xy 233.045 45.72)
		)
		(stroke
			(width 0)
			(type default)
		)
	)
	(wire
		(pts
			(xy 184.785 111.76) (xy 184.785 113.03)
		)
		(stroke
			(width 0)
			(type default)
		)
	)
	(bus
		(pts
			(xy 172.72 151.765) (xy 174.625 151.765)
		)
		(stroke
			(width 0)
			(type default)
		)
	)
	(wire
		(pts
			(xy 220.345 41.275) (xy 220.345 53.34)
		)
		(stroke
			(width 0)
			(type default)
		)
	)
	(wire
		(pts
			(xy 189.23 207.01) (xy 193.04 207.01)
		)
		(stroke
			(width 0)
			(type default)
		)
	)
	(wire
		(pts
			(xy 225.425 189.23) (xy 226.06 189.23)
		)
		(stroke
			(width 0)
			(type default)
		)
	)
	(wire
		(pts
			(xy 177.8 109.22) (xy 186.055 109.22)
		)
		(stroke
			(width 0)
			(type default)
		)
	)
	(wire
		(pts
			(xy 234.315 74.295) (xy 234.315 72.39)
		)
		(stroke
			(width 0)
			(type default)
		)
	)
	(bus
		(pts
			(xy 175.26 161.29) (xy 175.26 163.83)
		)
		(stroke
			(width 0)
			(type default)
		)
	)
	(bus
		(pts
			(xy 174.625 46.355) (xy 175.26 46.99)
		)
		(stroke
			(width 0)
			(type default)
		)
	)
	(wire
		(pts
			(xy 220.345 53.34) (xy 234.95 53.34)
		)
		(stroke
			(width 0)
			(type default)
		)
	)
	(bus
		(pts
			(xy 175.26 153.67) (xy 175.26 156.21)
		)
		(stroke
			(width 0)
			(type default)
		)
	)
	(wire
		(pts
			(xy 198.12 166.37) (xy 226.06 166.37)
		)
		(stroke
			(width 0)
			(type default)
		)
	)
	(bus
		(pts
			(xy 175.26 50.8) (xy 175.26 53.34)
		)
		(stroke
			(width 0)
			(type default)
		)
	)
	(wire
		(pts
			(xy 208.915 215.9) (xy 208.915 217.805)
		)
		(stroke
			(width 0)
			(type default)
		)
	)
	(wire
		(pts
			(xy 194.945 63.5) (xy 234.95 63.5)
		)
		(stroke
			(width 0)
			(type default)
		)
	)
	(wire
		(pts
			(xy 208.915 207.01) (xy 226.06 207.01)
		)
		(stroke
			(width 0)
			(type default)
		)
	)
	(bus
		(pts
			(xy 175.26 46.99) (xy 175.26 48.26)
		)
		(stroke
			(width 0)
			(type default)
		)
	)
	(wire
		(pts
			(xy 226.695 36.195) (xy 226.695 31.115)
		)
		(stroke
			(width 0)
			(type default)
		)
	)
	(wire
		(pts
			(xy 251.46 207.01) (xy 257.81 207.01)
		)
		(stroke
			(width 0)
			(type default)
		)
	)
	(label "HDMI_CONN_D1_P"
		(at 207.01 163.83 0)
		(effects
			(font
				(size 1.27 1.27)
			)
			(justify left bottom)
		)
	)
	(label "SD.DAT2"
		(at 177.8 109.22 0)
		(effects
			(font
				(size 1.27 1.27)
			)
			(justify left bottom)
		)
	)
	(label "HDMI_CONN_D2_P"
		(at 207.01 156.21 0)
		(effects
			(font
				(size 1.27 1.27)
			)
			(justify left bottom)
		)
	)
	(label "HDMI_CONN_D2_N"
		(at 177.8 234.315 0)
		(effects
			(font
				(size 1.27 1.27)
			)
			(justify left bottom)
		)
	)
	(label "SD.DAT3"
		(at 177.8 53.34 0)
		(effects
			(font
				(size 1.27 1.27)
			)
			(justify left bottom)
		)
	)
	(label "SD.CMD"
		(at 177.8 55.88 0)
		(effects
			(font
				(size 1.27 1.27)
			)
			(justify left bottom)
		)
	)
	(label "SD.DAT2"
		(at 177.8 50.8 0)
		(effects
			(font
				(size 1.27 1.27)
			)
			(justify left bottom)
		)
	)
	(label "SD.CD"
		(at 177.8 66.04 0)
		(effects
			(font
				(size 1.27 1.27)
			)
			(justify left bottom)
		)
	)
	(label "HDMI_CONN_D0_N"
		(at 207.01 173.99 0)
		(effects
			(font
				(size 1.27 1.27)
			)
			(justify left bottom)
		)
	)
	(label "SD.DAT0"
		(at 177.8 83.82 0)
		(effects
			(font
				(size 1.27 1.27)
			)
			(justify left bottom)
		)
	)
	(label "HDMI_CONN_D1_N"
		(at 177.8 239.395 0)
		(effects
			(font
				(size 1.27 1.27)
			)
			(justify left bottom)
		)
	)
	(label "SD.CD"
		(at 177.8 78.74 0)
		(effects
			(font
				(size 1.27 1.27)
			)
			(justify left bottom)
		)
	)
	(label "SD.DAT1"
		(at 177.8 63.5 0)
		(effects
			(font
				(size 1.27 1.27)
			)
			(justify left bottom)
		)
	)
	(label "SD.DAT0"
		(at 177.8 60.96 0)
		(effects
			(font
				(size 1.27 1.27)
			)
			(justify left bottom)
		)
	)
	(label "HDMI.D2_N"
		(at 177.8 158.75 0)
		(effects
			(font
				(size 1.27 1.27)
			)
			(justify left bottom)
		)
	)
	(label "HDMI_CONN_D0_P"
		(at 207.01 171.45 0)
		(effects
			(font
				(size 1.27 1.27)
			)
			(justify left bottom)
		)
	)
	(label "SD.DAT1"
		(at 177.8 81.28 0)
		(effects
			(font
				(size 1.27 1.27)
			)
			(justify left bottom)
		)
	)
	(label "HDMI.D0_P"
		(at 177.8 171.45 0)
		(effects
			(font
				(size 1.27 1.27)
			)
			(justify left bottom)
		)
	)
	(label "HDMI_CONN_D0_P"
		(at 177.8 255.27 0)
		(effects
			(font
				(size 1.27 1.27)
			)
			(justify left bottom)
		)
	)
	(label "HDMI.D2_P"
		(at 177.8 156.21 0)
		(effects
			(font
				(size 1.27 1.27)
			)
			(justify left bottom)
		)
	)
	(label "HDMI.CLK_N"
		(at 177.8 181.61 0)
		(effects
			(font
				(size 1.27 1.27)
			)
			(justify left bottom)
		)
	)
	(label "HDMI_CONN_CLK_N"
		(at 207.01 181.61 0)
		(effects
			(font
				(size 1.27 1.27)
			)
			(justify left bottom)
		)
	)
	(label "HDMI_5V"
		(at 177.8 207.01 0)
		(effects
			(font
				(size 1.27 1.27)
			)
			(justify left bottom)
		)
	)
	(label "HDMI.D1_N"
		(at 177.8 166.37 0)
		(effects
			(font
				(size 1.27 1.27)
			)
			(justify left bottom)
		)
	)
	(label "HDMI_CONN_D2_N"
		(at 207.01 158.75 0)
		(effects
			(font
				(size 1.27 1.27)
			)
			(justify left bottom)
		)
	)
	(label "HDMI.CLK_P"
		(at 177.8 179.07 0)
		(effects
			(font
				(size 1.27 1.27)
			)
			(justify left bottom)
		)
	)
	(label "SD.CLK"
		(at 177.8 101.6 0)
		(effects
			(font
				(size 1.27 1.27)
			)
			(justify left bottom)
		)
	)
	(label "HDMI_CONN_D0_N"
		(at 177.8 257.81 0)
		(effects
			(font
				(size 1.27 1.27)
			)
			(justify left bottom)
		)
	)
	(label "HDMI_CONN_D1_P"
		(at 177.8 236.855 0)
		(effects
			(font
				(size 1.27 1.27)
			)
			(justify left bottom)
		)
	)
	(label "SD.CLK"
		(at 177.8 58.42 0)
		(effects
			(font
				(size 1.27 1.27)
			)
			(justify left bottom)
		)
	)
	(label "HDMI_CONN_CLK_P"
		(at 207.01 179.07 0)
		(effects
			(font
				(size 1.27 1.27)
			)
			(justify left bottom)
		)
	)
	(label "HDMI_CONN_CLK_N"
		(at 177.8 262.89 0)
		(effects
			(font
				(size 1.27 1.27)
			)
			(justify left bottom)
		)
	)
	(label "HDMI_CONN_D1_N"
		(at 207.01 166.37 0)
		(effects
			(font
				(size 1.27 1.27)
			)
			(justify left bottom)
		)
	)
	(label "HDMI_CONN_CLK_P"
		(at 177.8 260.35 0)
		(effects
			(font
				(size 1.27 1.27)
			)
			(justify left bottom)
		)
	)
	(label "SD.DAT3"
		(at 177.8 106.68 0)
		(effects
			(font
				(size 1.27 1.27)
			)
			(justify left bottom)
		)
	)
	(label "HDMI.D0_N"
		(at 177.8 173.99 0)
		(effects
			(font
				(size 1.27 1.27)
			)
			(justify left bottom)
		)
	)
	(label "HDMI.D1_P"
		(at 177.8 163.83 0)
		(effects
			(font
				(size 1.27 1.27)
			)
			(justify left bottom)
		)
	)
	(label "HDMI_CONN_5V"
		(at 210.82 207.01 0)
		(effects
			(font
				(size 1.27 1.27)
			)
			(justify left bottom)
		)
	)
	(label "SD.CMD"
		(at 177.8 104.14 0)
		(effects
			(font
				(size 1.27 1.27)
			)
			(justify left bottom)
		)
	)
	(label "HDMI_CONN_D2_P"
		(at 177.8 231.775 0)
		(effects
			(font
				(size 1.27 1.27)
			)
			(justify left bottom)
		)
	)
	(hierarchical_label "HDMI{TMDS}"
		(shape bidirectional)
		(at 172.72 151.765 180)
		(effects
			(font
				(size 1.27 1.27)
			)
			(justify right)
		)
	)
	(hierarchical_label "SD{SDIO}"
		(shape bidirectional)
		(at 172.72 46.355 180)
		(effects
			(font
				(size 1.27 1.27)
			)
			(justify right)
		)
	)
	(symbol
		(lib_id "antmicroResistors0402:R_0R_0402")
		(at 193.04 179.07 0)
		(unit 1)
		(exclude_from_sim no)
		(in_bom yes)
		(on_board yes)
		(dnp no)
		(property "Reference" "R76"
			(at 198.12 177.8 0)
			(effects
				(font
					(size 1.27 1.27)
				)
				(justify left)
			)
		)
		(property "Value" "R_0R_0402"
			(at 213.36 191.77 0)
			(effects
				(font
					(size 1.27 1.27)
					(thickness 0.15)
				)
				(justify left bottom)
				(hide yes)
			)
		)
		(property "Footprint" "antmicro-footprints:R_0402_1005Metric"
			(at 213.36 194.31 0)
			(effects
				(font
					(size 1.27 1.27)
					(thickness 0.15)
				)
				(justify left bottom)
				(hide yes)
			)
		)
		(property "Datasheet" "https://industrial.panasonic.com/cdbs/www-data/pdf/RDA0000/AOA0000C301.pdf"
			(at 213.36 196.85 0)
			(effects
				(font
					(size 1.27 1.27)
					(thickness 0.15)
				)
				(justify left bottom)
				(hide yes)
			)
		)
		(property "Description" ""
			(at 193.04 179.07 0)
			(effects
				(font
					(size 1.27 1.27)
				)
			)
		)
		(property "Manufacturer" "Panasonic"
			(at 213.36 201.93 0)
			(effects
				(font
					(size 1.27 1.27)
					(thickness 0.15)
				)
				(justify left bottom)
				(hide yes)
			)
		)
		(property "MPN" "ERJ2GE0R00X"
			(at 213.36 199.39 0)
			(effects
				(font
					(size 1.27 1.27)
					(thickness 0.15)
				)
				(justify left bottom)
				(hide yes)
			)
		)
		(property "Val" "0R"
			(at 190.5 177.8 0)
			(effects
				(font
					(size 1.27 1.27)
					(thickness 0.15)
				)
				(justify left)
			)
		)
		(property "License" "Apache-2.0"
			(at 213.36 204.47 0)
			(effects
				(font
					(size 1.27 1.27)
					(thickness 0.15)
				)
				(justify left bottom)
				(hide yes)
			)
		)
		(property "Author" "Antmicro"
			(at 213.36 207.01 0)
			(effects
				(font
					(size 1.27 1.27)
					(thickness 0.15)
				)
				(justify left bottom)
				(hide yes)
			)
		)
		(property "Tolerance" "~"
			(at 213.36 189.23 0)
			(effects
				(font
					(size 1.27 1.27)
				)
				(justify left bottom)
				(hide yes)
			)
		)
		(property "Current" "1A"
			(at 213.36 209.55 0)
			(effects
				(font
					(size 1.27 1.27)
					(thickness 0.15)
				)
				(justify left bottom)
				(hide yes)
			)
		)
		(pin "1"
		)
		(pin "2"
		)
		(instances
			(project "sodimm-ddr5-tester"
				(path ""
					(reference "R76")
					(unit 1)
				)
			)
		)
	)
	(symbol
		(lib_id "antmicroResistors0402:R_20k_0402")
		(at 220.345 36.195 270)
		(unit 1)
		(exclude_from_sim no)
		(in_bom yes)
		(on_board yes)
		(dnp no)
		(property "Reference" "R86"
			(at 220.345 35.56 90)
			(effects
				(font
					(size 1.27 1.27)
				)
				(justify left)
			)
		)
		(property "Value" "R_20k_0402"
			(at 207.645 56.515 0)
			(effects
				(font
					(size 1.27 1.27)
					(thickness 0.15)
				)
				(justify left bottom)
				(hide yes)
			)
		)
		(property "Footprint" "antmicro-footprints:R_0402_1005Metric"
			(at 205.105 56.515 0)
			(effects
				(font
					(size 1.27 1.27)
					(thickness 0.15)
				)
				(justify left bottom)
				(hide yes)
			)
		)
		(property "Datasheet" "https://www.bourns.com/docs/product-datasheets/cr.pdf"
			(at 202.565 56.515 0)
			(effects
				(font
					(size 1.27 1.27)
					(thickness 0.15)
				)
				(justify left bottom)
				(hide yes)
			)
		)
		(property "Description" ""
			(at 220.345 36.195 0)
			(effects
				(font
					(size 1.27 1.27)
				)
			)
		)
		(property "Manufacturer" "Bourns"
			(at 197.485 56.515 0)
			(effects
				(font
					(size 1.27 1.27)
					(thickness 0.15)
				)
				(justify left bottom)
				(hide yes)
			)
		)
		(property "MPN" "CR0402-FX-2002GLF"
			(at 200.025 56.515 0)
			(effects
				(font
					(size 1.27 1.27)
					(thickness 0.15)
				)
				(justify left bottom)
				(hide yes)
			)
		)
		(property "Val" "20k"
			(at 220.345 41.91 90)
			(effects
				(font
					(size 1.27 1.27)
					(thickness 0.15)
				)
				(justify left)
			)
		)
		(property "License" "Apache-2.0"
			(at 194.945 56.515 0)
			(effects
				(font
					(size 1.27 1.27)
					(thickness 0.15)
				)
				(justify left bottom)
				(hide yes)
			)
		)
		(property "Author" "Antmicro"
			(at 192.405 56.515 0)
			(effects
				(font
					(size 1.27 1.27)
					(thickness 0.15)
				)
				(justify left bottom)
				(hide yes)
			)
		)
		(property "Tolerance" "1%"
			(at 210.185 56.515 0)
			(effects
				(font
					(size 1.27 1.27)
				)
				(justify left bottom)
				(hide yes)
			)
		)
		(pin "1"
		)
		(pin "2"
		)
		(instances
			(project "sodimm-ddr5-tester"
				(path ""
					(reference "R86")
					(unit 1)
				)
			)
		)
	)
	(symbol
		(lib_id "antmicropower:GND")
		(at 234.315 74.295 0)
		(unit 1)
		(exclude_from_sim no)
		(in_bom yes)
		(on_board yes)
		(dnp no)
		(fields_autoplaced yes)
		(property "Reference" "#PWR0224"
			(at 234.315 80.645 0)
			(effects
				(font
					(size 1.27 1.27)
				)
				(hide yes)
			)
		)
		(property "Value" "GND"
			(at 236.22 75.565 0)
			(effects
				(font
					(size 1.27 1.27)
					(thickness 0.15)
				)
				(justify left)
			)
		)
		(property "Footprint" ""
			(at 243.205 81.915 0)
			(effects
				(font
					(size 1.27 1.27)
					(thickness 0.15)
				)
				(justify left bottom)
				(hide yes)
			)
		)
		(property "Datasheet" ""
			(at 243.205 86.995 0)
			(effects
				(font
					(size 1.27 1.27)
					(thickness 0.15)
				)
				(justify left bottom)
				(hide yes)
			)
		)
		(property "Description" ""
			(at 243.205 89.535 0)
			(effects
				(font
					(size 1.27 1.27)
				)
				(justify left bottom)
				(hide yes)
			)
		)
		(property "Author" "Antmicro"
			(at 243.205 81.915 0)
			(effects
				(font
					(size 1.27 1.27)
					(thickness 0.15)
				)
				(justify left bottom)
				(hide yes)
			)
		)
		(property "License" "Apache-2.0"
			(at 243.205 84.455 0)
			(effects
				(font
					(size 1.27 1.27)
					(thickness 0.15)
				)
				(justify left bottom)
				(hide yes)
			)
		)
		(pin "1"
		)
		(instances
			(project "sodimm-ddr5-tester"
				(path ""
					(reference "#PWR0224")
					(unit 1)
				)
			)
		)
	)
	(symbol
		(lib_id "antmicroResistors0402:R_0R_0402")
		(at 193.04 171.45 0)
		(unit 1)
		(exclude_from_sim no)
		(in_bom yes)
		(on_board yes)
		(dnp no)
		(property "Reference" "R74"
			(at 198.12 170.18 0)
			(effects
				(font
					(size 1.27 1.27)
				)
				(justify left)
			)
		)
		(property "Value" "R_0R_0402"
			(at 213.36 184.15 0)
			(effects
				(font
					(size 1.27 1.27)
					(thickness 0.15)
				)
				(justify left bottom)
				(hide yes)
			)
		)
		(property "Footprint" "antmicro-footprints:R_0402_1005Metric"
			(at 213.36 186.69 0)
			(effects
				(font
					(size 1.27 1.27)
					(thickness 0.15)
				)
				(justify left bottom)
				(hide yes)
			)
		)
		(property "Datasheet" "https://industrial.panasonic.com/cdbs/www-data/pdf/RDA0000/AOA0000C301.pdf"
			(at 213.36 189.23 0)
			(effects
				(font
					(size 1.27 1.27)
					(thickness 0.15)
				)
				(justify left bottom)
				(hide yes)
			)
		)
		(property "Description" ""
			(at 193.04 171.45 0)
			(effects
				(font
					(size 1.27 1.27)
				)
			)
		)
		(property "Manufacturer" "Panasonic"
			(at 213.36 194.31 0)
			(effects
				(font
					(size 1.27 1.27)
					(thickness 0.15)
				)
				(justify left bottom)
				(hide yes)
			)
		)
		(property "MPN" "ERJ2GE0R00X"
			(at 213.36 191.77 0)
			(effects
				(font
					(size 1.27 1.27)
					(thickness 0.15)
				)
				(justify left bottom)
				(hide yes)
			)
		)
		(property "Val" "0R"
			(at 190.5 170.18 0)
			(effects
				(font
					(size 1.27 1.27)
					(thickness 0.15)
				)
				(justify left)
			)
		)
		(property "License" "Apache-2.0"
			(at 213.36 196.85 0)
			(effects
				(font
					(size 1.27 1.27)
					(thickness 0.15)
				)
				(justify left bottom)
				(hide yes)
			)
		)
		(property "Author" "Antmicro"
			(at 213.36 199.39 0)
			(effects
				(font
					(size 1.27 1.27)
					(thickness 0.15)
				)
				(justify left bottom)
				(hide yes)
			)
		)
		(property "Tolerance" "~"
			(at 213.36 181.61 0)
			(effects
				(font
					(size 1.27 1.27)
				)
				(justify left bottom)
				(hide yes)
			)
		)
		(property "Current" "1A"
			(at 213.36 201.93 0)
			(effects
				(font
					(size 1.27 1.27)
					(thickness 0.15)
				)
				(justify left bottom)
				(hide yes)
			)
		)
		(pin "1"
		)
		(pin "2"
		)
		(instances
			(project "sodimm-ddr5-tester"
				(path ""
					(reference "R74")
					(unit 1)
				)
			)
		)
	)
	(symbol
		(lib_id "antmicroTVSDiodes:TPD4E05U06QDQARQ1")
		(at 196.85 255.27 0)
		(unit 1)
		(exclude_from_sim no)
		(in_bom yes)
		(on_board yes)
		(dnp no)
		(property "Reference" "U11"
			(at 207.645 258.4449 0)
			(effects
				(font
					(size 1.27 1.27)
				)
				(justify left)
			)
		)
		(property "Value" "TPD4E05U06QDQARQ1"
			(at 198.755 268.605 0)
			(effects
				(font
					(size 1.27 1.27)
					(thickness 0.15)
				)
				(justify left)
			)
		)
		(property "Footprint" "antmicro-footprints:USON-10_2.5x1mm_P0.5mm"
			(at 220.98 260.35 0)
			(effects
				(font
					(size 1.27 1.27)
					(thickness 0.15)
				)
				(justify left bottom)
				(hide yes)
			)
		)
		(property "Datasheet" "https://www.ti.com/lit/ds/symlink/tpd4e05u06-q1.pdf?HQS=dis-mous-null-mousermode-dsf-pf-null-wwe&ts=1663591265741&ref_url=https%253A%252F%252Fwww.mouser.com%252F"
			(at 220.98 262.89 0)
			(effects
				(font
					(size 1.27 1.27)
					(thickness 0.15)
				)
				(justify left bottom)
				(hide yes)
			)
		)
		(property "Description" ""
			(at 196.85 255.27 0)
			(effects
				(font
					(size 1.27 1.27)
				)
			)
		)
		(property "Manufacturer" "Texas Instruments"
			(at 220.98 265.43 0)
			(effects
				(font
					(size 1.27 1.27)
					(thickness 0.15)
				)
				(justify left bottom)
				(hide yes)
			)
		)
		(property "MPN" "TPD4E05U06QDQARQ1"
			(at 220.98 267.97 0)
			(effects
				(font
					(size 1.27 1.27)
					(thickness 0.15)
				)
				(justify left bottom)
				(hide yes)
			)
		)
		(property "Author" "Antmicro"
			(at 220.98 270.51 0)
			(effects
				(font
					(size 1.27 1.27)
					(thickness 0.15)
				)
				(justify left bottom)
				(hide yes)
			)
		)
		(property "License" "Apache-2.0"
			(at 220.98 273.05 0)
			(effects
				(font
					(size 1.27 1.27)
					(thickness 0.15)
				)
				(justify left bottom)
				(hide yes)
			)
		)
		(pin "1"
		)
		(pin "10"
		)
		(pin "2"
		)
		(pin "3"
		)
		(pin "4"
		)
		(pin "5"
		)
		(pin "6"
		)
		(pin "7"
		)
		(pin "8"
		)
		(pin "9"
		)
		(instances
			(project "sodimm-ddr5-tester"
				(path ""
					(reference "U11")
					(unit 1)
				)
			)
		)
	)
	(symbol
		(lib_id "antmicroVideoConnectors:HDMI-A_WE_685119134923")
		(at 226.06 156.21 0)
		(unit 1)
		(exclude_from_sim no)
		(in_bom yes)
		(on_board yes)
		(dnp no)
		(fields_autoplaced yes)
		(property "Reference" "J4"
			(at 238.76 149.985 0)
			(effects
				(font
					(size 1.27 1.27)
					(thickness 0.15)
				)
			)
		)
		(property "Value" "HDMI-A_WE_685119134923"
			(at 238.76 152.5087 0)
			(effects
				(font
					(size 1.27 1.27)
					(thickness 0.15)
				)
			)
		)
		(property "Footprint" "antmicro-footprints:HDMI-A_Receptacle_WE_685119134923"
			(at 261.62 163.83 0)
			(effects
				(font
					(size 1.27 1.27)
					(thickness 0.15)
				)
				(justify left bottom)
				(hide yes)
			)
		)
		(property "Datasheet" "https://www.we-online.com/components/products/datasheet/685119134923.pdf"
			(at 261.62 166.37 0)
			(effects
				(font
					(size 1.27 1.27)
					(thickness 0.15)
				)
				(justify left bottom)
				(hide yes)
			)
		)
		(property "Description" ""
			(at 226.06 156.21 0)
			(effects
				(font
					(size 1.27 1.27)
				)
			)
		)
		(property "MPN" "685119134923"
			(at 261.62 168.91 0)
			(effects
				(font
					(size 1.27 1.27)
					(thickness 0.15)
				)
				(justify left bottom)
				(hide yes)
			)
		)
		(property "Manufacturer" "Würth Elektronik"
			(at 261.62 171.45 0)
			(effects
				(font
					(size 1.27 1.27)
					(thickness 0.15)
				)
				(justify left bottom)
				(hide yes)
			)
		)
		(property "Author" "Antmicro"
			(at 261.62 173.99 0)
			(effects
				(font
					(size 1.27 1.27)
					(thickness 0.15)
				)
				(justify left bottom)
				(hide yes)
			)
		)
		(property "License" "Apache-2.0"
			(at 261.62 176.53 0)
			(effects
				(font
					(size 1.27 1.27)
					(thickness 0.15)
				)
				(justify left bottom)
				(hide yes)
			)
		)
		(pin "1"
		)
		(pin "10"
		)
		(pin "11"
		)
		(pin "12"
		)
		(pin "13"
		)
		(pin "14"
		)
		(pin "15"
		)
		(pin "16"
		)
		(pin "17"
		)
		(pin "18"
		)
		(pin "19"
		)
		(pin "2"
		)
		(pin "3"
		)
		(pin "4"
		)
		(pin "5"
		)
		(pin "6"
		)
		(pin "7"
		)
		(pin "8"
		)
		(pin "9"
		)
		(pin "SH"
		)
		(instances
			(project "sodimm-ddr5-tester"
				(path ""
					(reference "J4")
					(unit 1)
				)
			)
		)
	)
	(symbol
		(lib_id "antmicroResistors0402:R_0R_0402")
		(at 193.04 166.37 0)
		(unit 1)
		(exclude_from_sim no)
		(in_bom yes)
		(on_board yes)
		(dnp no)
		(property "Reference" "R73"
			(at 198.12 165.1 0)
			(effects
				(font
					(size 1.27 1.27)
				)
				(justify left)
			)
		)
		(property "Value" "R_0R_0402"
			(at 213.36 179.07 0)
			(effects
				(font
					(size 1.27 1.27)
					(thickness 0.15)
				)
				(justify left bottom)
				(hide yes)
			)
		)
		(property "Footprint" "antmicro-footprints:R_0402_1005Metric"
			(at 213.36 181.61 0)
			(effects
				(font
					(size 1.27 1.27)
					(thickness 0.15)
				)
				(justify left bottom)
				(hide yes)
			)
		)
		(property "Datasheet" "https://industrial.panasonic.com/cdbs/www-data/pdf/RDA0000/AOA0000C301.pdf"
			(at 213.36 184.15 0)
			(effects
				(font
					(size 1.27 1.27)
					(thickness 0.15)
				)
				(justify left bottom)
				(hide yes)
			)
		)
		(property "Description" ""
			(at 193.04 166.37 0)
			(effects
				(font
					(size 1.27 1.27)
				)
			)
		)
		(property "Manufacturer" "Panasonic"
			(at 213.36 189.23 0)
			(effects
				(font
					(size 1.27 1.27)
					(thickness 0.15)
				)
				(justify left bottom)
				(hide yes)
			)
		)
		(property "MPN" "ERJ2GE0R00X"
			(at 213.36 186.69 0)
			(effects
				(font
					(size 1.27 1.27)
					(thickness 0.15)
				)
				(justify left bottom)
				(hide yes)
			)
		)
		(property "Val" "0R"
			(at 190.5 165.1 0)
			(effects
				(font
					(size 1.27 1.27)
					(thickness 0.15)
				)
				(justify left)
			)
		)
		(property "License" "Apache-2.0"
			(at 213.36 191.77 0)
			(effects
				(font
					(size 1.27 1.27)
					(thickness 0.15)
				)
				(justify left bottom)
				(hide yes)
			)
		)
		(property "Author" "Antmicro"
			(at 213.36 194.31 0)
			(effects
				(font
					(size 1.27 1.27)
					(thickness 0.15)
				)
				(justify left bottom)
				(hide yes)
			)
		)
		(property "Tolerance" "~"
			(at 213.36 176.53 0)
			(effects
				(font
					(size 1.27 1.27)
				)
				(justify left bottom)
				(hide yes)
			)
		)
		(property "Current" "1A"
			(at 213.36 196.85 0)
			(effects
				(font
					(size 1.27 1.27)
					(thickness 0.15)
				)
				(justify left bottom)
				(hide yes)
			)
		)
		(pin "1"
		)
		(pin "2"
		)
		(instances
			(project "sodimm-ddr5-tester"
				(path ""
					(reference "R73")
					(unit 1)
				)
			)
		)
	)
	(symbol
		(lib_id "antmicropower:GND")
		(at 177.165 38.1 0)
		(unit 1)
		(exclude_from_sim no)
		(in_bom yes)
		(on_board yes)
		(dnp no)
		(fields_autoplaced yes)
		(property "Reference" "#PWR0217"
			(at 177.165 44.45 0)
			(effects
				(font
					(size 1.27 1.27)
				)
				(hide yes)
			)
		)
		(property "Value" "GND"
			(at 179.07 39.37 0)
			(effects
				(font
					(size 1.27 1.27)
					(thickness 0.15)
				)
				(justify left)
			)
		)
		(property "Footprint" ""
			(at 186.055 45.72 0)
			(effects
				(font
					(size 1.27 1.27)
					(thickness 0.15)
				)
				(justify left bottom)
				(hide yes)
			)
		)
		(property "Datasheet" ""
			(at 186.055 50.8 0)
			(effects
				(font
					(size 1.27 1.27)
					(thickness 0.15)
				)
				(justify left bottom)
				(hide yes)
			)
		)
		(property "Description" ""
			(at 186.055 53.34 0)
			(effects
				(font
					(size 1.27 1.27)
				)
				(justify left bottom)
				(hide yes)
			)
		)
		(property "Author" "Antmicro"
			(at 186.055 45.72 0)
			(effects
				(font
					(size 1.27 1.27)
					(thickness 0.15)
				)
				(justify left bottom)
				(hide yes)
			)
		)
		(property "License" "Apache-2.0"
			(at 186.055 48.26 0)
			(effects
				(font
					(size 1.27 1.27)
					(thickness 0.15)
				)
				(justify left bottom)
				(hide yes)
			)
		)
		(pin "1"
		)
		(instances
			(project "sodimm-ddr5-tester"
				(path ""
					(reference "#PWR0217")
					(unit 1)
				)
			)
		)
	)
	(symbol
		(lib_id "antmicroTestPoints:TP_1mm_SMD")
		(at 201.93 206.375 90)
		(unit 1)
		(exclude_from_sim no)
		(in_bom yes)
		(on_board yes)
		(dnp no)
		(fields_autoplaced yes)
		(property "Reference" "TP2"
			(at 201.93 201.4022 90)
			(effects
				(font
					(size 1.27 1.27)
				)
			)
		)
		(property "Value" "TP_1mm_SMD"
			(at 209.55 191.135 0)
			(effects
				(font
					(size 1.27 1.27)
					(thickness 0.15)
				)
				(justify left bottom)
				(hide yes)
			)
		)
		(property "Footprint" "antmicro-footprints:TP_SMD_1mm"
			(at 212.09 191.135 0)
			(effects
				(font
					(size 1.27 1.27)
					(thickness 0.15)
				)
				(justify left bottom)
				(hide yes)
			)
		)
		(property "Datasheet" ""
			(at 214.63 191.135 0)
			(effects
				(font
					(size 1.27 1.27)
					(thickness 0.15)
				)
				(justify left bottom)
				(hide yes)
			)
		)
		(property "Description" ""
			(at 201.93 206.375 0)
			(effects
				(font
					(size 1.27 1.27)
				)
			)
		)
		(property "MPN" ""
			(at 201.93 206.375 0)
			(effects
				(font
					(size 1.27 1.27)
				)
				(hide yes)
			)
		)
		(property "Manufacturer" ""
			(at 201.93 206.375 0)
			(effects
				(font
					(size 1.27 1.27)
				)
				(hide yes)
			)
		)
		(property "Author" "Antmicro"
			(at 217.17 191.135 0)
			(effects
				(font
					(size 1.27 1.27)
					(thickness 0.15)
				)
				(justify left bottom)
				(hide yes)
			)
		)
		(property "License" "Apache-2.0"
			(at 219.71 191.135 0)
			(effects
				(font
					(size 1.27 1.27)
					(thickness 0.15)
				)
				(justify left bottom)
				(hide yes)
			)
		)
		(pin "1"
		)
		(instances
			(project "sodimm-ddr5-tester"
				(path ""
					(reference "TP2")
					(unit 1)
				)
			)
		)
	)
	(symbol
		(lib_id "antmicroResistors0402:R_20k_0402")
		(at 201.295 36.195 270)
		(unit 1)
		(exclude_from_sim no)
		(in_bom yes)
		(on_board yes)
		(dnp no)
		(property "Reference" "R82"
			(at 201.295 35.56 90)
			(effects
				(font
					(size 1.27 1.27)
				)
				(justify left)
			)
		)
		(property "Value" "R_20k_0402"
			(at 188.595 56.515 0)
			(effects
				(font
					(size 1.27 1.27)
					(thickness 0.15)
				)
				(justify left bottom)
				(hide yes)
			)
		)
		(property "Footprint" "antmicro-footprints:R_0402_1005Metric"
			(at 186.055 56.515 0)
			(effects
				(font
					(size 1.27 1.27)
					(thickness 0.15)
				)
				(justify left bottom)
				(hide yes)
			)
		)
		(property "Datasheet" "https://www.bourns.com/docs/product-datasheets/cr.pdf"
			(at 183.515 56.515 0)
			(effects
				(font
					(size 1.27 1.27)
					(thickness 0.15)
				)
				(justify left bottom)
				(hide yes)
			)
		)
		(property "Description" ""
			(at 201.295 36.195 0)
			(effects
				(font
					(size 1.27 1.27)
				)
			)
		)
		(property "Manufacturer" "Bourns"
			(at 178.435 56.515 0)
			(effects
				(font
					(size 1.27 1.27)
					(thickness 0.15)
				)
				(justify left bottom)
				(hide yes)
			)
		)
		(property "MPN" "CR0402-FX-2002GLF"
			(at 180.975 56.515 0)
			(effects
				(font
					(size 1.27 1.27)
					(thickness 0.15)
				)
				(justify left bottom)
				(hide yes)
			)
		)
		(property "Val" "20k"
			(at 201.295 41.91 90)
			(effects
				(font
					(size 1.27 1.27)
					(thickness 0.15)
				)
				(justify left)
			)
		)
		(property "License" "Apache-2.0"
			(at 175.895 56.515 0)
			(effects
				(font
					(size 1.27 1.27)
					(thickness 0.15)
				)
				(justify left bottom)
				(hide yes)
			)
		)
		(property "Author" "Antmicro"
			(at 173.355 56.515 0)
			(effects
				(font
					(size 1.27 1.27)
					(thickness 0.15)
				)
				(justify left bottom)
				(hide yes)
			)
		)
		(property "Tolerance" "1%"
			(at 191.135 56.515 0)
			(effects
				(font
					(size 1.27 1.27)
				)
				(justify left bottom)
				(hide yes)
			)
		)
		(pin "1"
		)
		(pin "2"
		)
		(instances
			(project "sodimm-ddr5-tester"
				(path ""
					(reference "R82")
					(unit 1)
				)
			)
		)
	)
	(symbol
		(lib_id "antmicroResistors0402:R_0R_0402")
		(at 193.04 163.83 0)
		(unit 1)
		(exclude_from_sim no)
		(in_bom yes)
		(on_board yes)
		(dnp no)
		(property "Reference" "R72"
			(at 198.12 162.56 0)
			(effects
				(font
					(size 1.27 1.27)
				)
				(justify left)
			)
		)
		(property "Value" "R_0R_0402"
			(at 213.36 176.53 0)
			(effects
				(font
					(size 1.27 1.27)
					(thickness 0.15)
				)
				(justify left bottom)
				(hide yes)
			)
		)
		(property "Footprint" "antmicro-footprints:R_0402_1005Metric"
			(at 213.36 179.07 0)
			(effects
				(font
					(size 1.27 1.27)
					(thickness 0.15)
				)
				(justify left bottom)
				(hide yes)
			)
		)
		(property "Datasheet" "https://industrial.panasonic.com/cdbs/www-data/pdf/RDA0000/AOA0000C301.pdf"
			(at 213.36 181.61 0)
			(effects
				(font
					(size 1.27 1.27)
					(thickness 0.15)
				)
				(justify left bottom)
				(hide yes)
			)
		)
		(property "Description" ""
			(at 193.04 163.83 0)
			(effects
				(font
					(size 1.27 1.27)
				)
			)
		)
		(property "Manufacturer" "Panasonic"
			(at 213.36 186.69 0)
			(effects
				(font
					(size 1.27 1.27)
					(thickness 0.15)
				)
				(justify left bottom)
				(hide yes)
			)
		)
		(property "MPN" "ERJ2GE0R00X"
			(at 213.36 184.15 0)
			(effects
				(font
					(size 1.27 1.27)
					(thickness 0.15)
				)
				(justify left bottom)
				(hide yes)
			)
		)
		(property "Val" "0R"
			(at 190.5 162.56 0)
			(effects
				(font
					(size 1.27 1.27)
					(thickness 0.15)
				)
				(justify left)
			)
		)
		(property "License" "Apache-2.0"
			(at 213.36 189.23 0)
			(effects
				(font
					(size 1.27 1.27)
					(thickness 0.15)
				)
				(justify left bottom)
				(hide yes)
			)
		)
		(property "Author" "Antmicro"
			(at 213.36 191.77 0)
			(effects
				(font
					(size 1.27 1.27)
					(thickness 0.15)
				)
				(justify left bottom)
				(hide yes)
			)
		)
		(property "Tolerance" "~"
			(at 213.36 173.99 0)
			(effects
				(font
					(size 1.27 1.27)
				)
				(justify left bottom)
				(hide yes)
			)
		)
		(property "Current" "1A"
			(at 213.36 194.31 0)
			(effects
				(font
					(size 1.27 1.27)
					(thickness 0.15)
				)
				(justify left bottom)
				(hide yes)
			)
		)
		(pin "1"
		)
		(pin "2"
		)
		(instances
			(project "sodimm-ddr5-tester"
				(path ""
					(reference "R72")
					(unit 1)
				)
			)
		)
	)
	(symbol
		(lib_id "antmicroResistors0402:R_20k_0402")
		(at 188.595 36.195 270)
		(unit 1)
		(exclude_from_sim no)
		(in_bom yes)
		(on_board yes)
		(dnp no)
		(property "Reference" "R80"
			(at 188.595 35.56 90)
			(effects
				(font
					(size 1.27 1.27)
				)
				(justify left)
			)
		)
		(property "Value" "R_20k_0402"
			(at 175.895 56.515 0)
			(effects
				(font
					(size 1.27 1.27)
					(thickness 0.15)
				)
				(justify left bottom)
				(hide yes)
			)
		)
		(property "Footprint" "antmicro-footprints:R_0402_1005Metric"
			(at 173.355 56.515 0)
			(effects
				(font
					(size 1.27 1.27)
					(thickness 0.15)
				)
				(justify left bottom)
				(hide yes)
			)
		)
		(property "Datasheet" "https://www.bourns.com/docs/product-datasheets/cr.pdf"
			(at 170.815 56.515 0)
			(effects
				(font
					(size 1.27 1.27)
					(thickness 0.15)
				)
				(justify left bottom)
				(hide yes)
			)
		)
		(property "Description" ""
			(at 188.595 36.195 0)
			(effects
				(font
					(size 1.27 1.27)
				)
			)
		)
		(property "Manufacturer" "Bourns"
			(at 165.735 56.515 0)
			(effects
				(font
					(size 1.27 1.27)
					(thickness 0.15)
				)
				(justify left bottom)
				(hide yes)
			)
		)
		(property "MPN" "CR0402-FX-2002GLF"
			(at 168.275 56.515 0)
			(effects
				(font
					(size 1.27 1.27)
					(thickness 0.15)
				)
				(justify left bottom)
				(hide yes)
			)
		)
		(property "Val" "20k"
			(at 188.595 41.91 90)
			(effects
				(font
					(size 1.27 1.27)
					(thickness 0.15)
				)
				(justify left)
			)
		)
		(property "License" "Apache-2.0"
			(at 163.195 56.515 0)
			(effects
				(font
					(size 1.27 1.27)
					(thickness 0.15)
				)
				(justify left bottom)
				(hide yes)
			)
		)
		(property "Author" "Antmicro"
			(at 160.655 56.515 0)
			(effects
				(font
					(size 1.27 1.27)
					(thickness 0.15)
				)
				(justify left bottom)
				(hide yes)
			)
		)
		(property "Tolerance" "1%"
			(at 178.435 56.515 0)
			(effects
				(font
					(size 1.27 1.27)
				)
				(justify left bottom)
				(hide yes)
			)
		)
		(pin "1"
		)
		(pin "2"
		)
		(instances
			(project "sodimm-ddr5-tester"
				(path ""
					(reference "R80")
					(unit 1)
				)
			)
		)
	)
	(symbol
		(lib_id "antmicropower:GND")
		(at 195.58 243.205 0)
		(unit 1)
		(exclude_from_sim no)
		(in_bom yes)
		(on_board yes)
		(dnp no)
		(property "Reference" "#PWR0219"
			(at 195.58 249.555 0)
			(effects
				(font
					(size 1.27 1.27)
				)
				(hide yes)
			)
		)
		(property "Value" "GND"
			(at 193.675 247.65 0)
			(effects
				(font
					(size 1.27 1.27)
					(thickness 0.15)
				)
				(justify left bottom)
			)
		)
		(property "Footprint" ""
			(at 204.47 250.825 0)
			(effects
				(font
					(size 1.27 1.27)
					(thickness 0.15)
				)
				(justify left bottom)
				(hide yes)
			)
		)
		(property "Datasheet" ""
			(at 204.47 255.905 0)
			(effects
				(font
					(size 1.27 1.27)
					(thickness 0.15)
				)
				(justify left bottom)
				(hide yes)
			)
		)
		(property "Description" ""
			(at 204.47 258.445 0)
			(effects
				(font
					(size 1.27 1.27)
				)
				(justify left bottom)
				(hide yes)
			)
		)
		(property "Author" "Antmicro"
			(at 204.47 250.825 0)
			(effects
				(font
					(size 1.27 1.27)
					(thickness 0.15)
				)
				(justify left bottom)
				(hide yes)
			)
		)
		(property "License" "Apache-2.0"
			(at 204.47 253.365 0)
			(effects
				(font
					(size 1.27 1.27)
					(thickness 0.15)
				)
				(justify left bottom)
				(hide yes)
			)
		)
		(pin "1"
		)
		(instances
			(project "sodimm-ddr5-tester"
				(path ""
					(reference "#PWR0219")
					(unit 1)
				)
			)
		)
	)
	(symbol
		(lib_id "antmicroResistors0402:R_0R_0402")
		(at 193.04 181.61 0)
		(unit 1)
		(exclude_from_sim no)
		(in_bom yes)
		(on_board yes)
		(dnp no)
		(property "Reference" "R77"
			(at 201.93 180.34 0)
			(effects
				(font
					(size 1.27 1.27)
				)
			)
		)
		(property "Value" "R_0R_0402"
			(at 213.36 194.31 0)
			(effects
				(font
					(size 1.27 1.27)
					(thickness 0.15)
				)
				(justify left bottom)
				(hide yes)
			)
		)
		(property "Footprint" "antmicro-footprints:R_0402_1005Metric"
			(at 213.36 196.85 0)
			(effects
				(font
					(size 1.27 1.27)
					(thickness 0.15)
				)
				(justify left bottom)
				(hide yes)
			)
		)
		(property "Datasheet" "https://industrial.panasonic.com/cdbs/www-data/pdf/RDA0000/AOA0000C301.pdf"
			(at 213.36 199.39 0)
			(effects
				(font
					(size 1.27 1.27)
					(thickness 0.15)
				)
				(justify left bottom)
				(hide yes)
			)
		)
		(property "Description" ""
			(at 193.04 181.61 0)
			(effects
				(font
					(size 1.27 1.27)
				)
			)
		)
		(property "Manufacturer" "Panasonic"
			(at 213.36 204.47 0)
			(effects
				(font
					(size 1.27 1.27)
					(thickness 0.15)
				)
				(justify left bottom)
				(hide yes)
			)
		)
		(property "MPN" "ERJ2GE0R00X"
			(at 213.36 201.93 0)
			(effects
				(font
					(size 1.27 1.27)
					(thickness 0.15)
				)
				(justify left bottom)
				(hide yes)
			)
		)
		(property "Val" "0R"
			(at 191.77 180.34 0)
			(effects
				(font
					(size 1.27 1.27)
					(thickness 0.15)
				)
			)
		)
		(property "License" "Apache-2.0"
			(at 213.36 207.01 0)
			(effects
				(font
					(size 1.27 1.27)
					(thickness 0.15)
				)
				(justify left bottom)
				(hide yes)
			)
		)
		(property "Author" "Antmicro"
			(at 213.36 209.55 0)
			(effects
				(font
					(size 1.27 1.27)
					(thickness 0.15)
				)
				(justify left bottom)
				(hide yes)
			)
		)
		(property "Tolerance" "~"
			(at 213.36 191.77 0)
			(effects
				(font
					(size 1.27 1.27)
				)
				(justify left bottom)
				(hide yes)
			)
		)
		(property "Current" "1A"
			(at 213.36 212.09 0)
			(effects
				(font
					(size 1.27 1.27)
					(thickness 0.15)
				)
				(justify left bottom)
				(hide yes)
			)
		)
		(pin "1"
		)
		(pin "2"
		)
		(instances
			(project "sodimm-ddr5-tester"
				(path ""
					(reference "R77")
					(unit 1)
				)
			)
		)
	)
	(symbol
		(lib_id "antmicroCapacitors0402:C_1u_0402")
		(at 177.165 31.75 270)
		(unit 1)
		(exclude_from_sim no)
		(in_bom yes)
		(on_board yes)
		(dnp no)
		(fields_autoplaced yes)
		(property "Reference" "C129"
			(at 179.705 33.0263 90)
			(effects
				(font
					(size 1.27 1.27)
				)
				(justify left)
			)
		)
		(property "Value" "C_1u_0402"
			(at 167.005 52.07 0)
			(effects
				(font
					(size 1.27 1.27)
					(thickness 0.15)
				)
				(justify left bottom)
				(hide yes)
			)
		)
		(property "Footprint" "antmicro-footprints:C_0402_1005Metric"
			(at 164.465 52.07 0)
			(effects
				(font
					(size 1.27 1.27)
					(thickness 0.15)
				)
				(justify left bottom)
				(hide yes)
			)
		)
		(property "Datasheet" "https://product.tdk.com/en/search/capacitor/ceramic/mlcc/info?part_no=C1005X6S1A105K050BC"
			(at 161.925 52.07 0)
			(effects
				(font
					(size 1.27 1.27)
					(thickness 0.15)
				)
				(justify left bottom)
				(hide yes)
			)
		)
		(property "Description" ""
			(at 177.165 31.75 0)
			(effects
				(font
					(size 1.27 1.27)
				)
			)
		)
		(property "Manufacturer" "TDK"
			(at 156.845 52.07 0)
			(effects
				(font
					(size 1.27 1.27)
					(thickness 0.15)
				)
				(justify left bottom)
				(hide yes)
			)
		)
		(property "MPN" "C1005X6S1A105K050BC"
			(at 159.385 52.07 0)
			(effects
				(font
					(size 1.27 1.27)
					(thickness 0.15)
				)
				(justify left bottom)
				(hide yes)
			)
		)
		(property "Val" "1u"
			(at 179.705 36.2012 90)
			(effects
				(font
					(size 1.27 1.27)
					(thickness 0.15)
				)
				(justify left)
			)
		)
		(property "License" "Apache-2.0"
			(at 154.305 52.07 0)
			(effects
				(font
					(size 1.27 1.27)
					(thickness 0.15)
				)
				(justify left bottom)
				(hide yes)
			)
		)
		(property "Author" "Antmicro"
			(at 151.765 52.07 0)
			(effects
				(font
					(size 1.27 1.27)
					(thickness 0.15)
				)
				(justify left bottom)
				(hide yes)
			)
		)
		(property "Voltage" ""
			(at 149.225 52.07 0)
			(effects
				(font
					(size 1.27 1.27)
				)
				(justify left bottom)
				(hide yes)
			)
		)
		(property "Dielectric" ""
			(at 146.685 52.07 0)
			(effects
				(font
					(size 1.27 1.27)
				)
				(justify left bottom)
				(hide yes)
			)
		)
		(pin "1"
		)
		(pin "2"
		)
		(instances
			(project "sodimm-ddr5-tester"
				(path ""
					(reference "C129")
					(unit 1)
				)
			)
		)
	)
	(symbol
		(lib_id "antmicroCapacitors0402:C_10u_6.3V_0402")
		(at 208.915 215.9 90)
		(unit 1)
		(exclude_from_sim no)
		(in_bom yes)
		(on_board yes)
		(dnp no)
		(fields_autoplaced yes)
		(property "Reference" "C126"
			(at 211.2391 212.523 90)
			(effects
				(font
					(size 1.27 1.27)
					(thickness 0.15)
				)
				(justify right)
			)
		)
		(property "Value" "C_10u_6.3V_0402"
			(at 219.075 195.58 0)
			(effects
				(font
					(size 1.27 1.27)
					(thickness 0.15)
				)
				(justify left bottom)
				(hide yes)
			)
		)
		(property "Footprint" "antmicro-footprints:C_0402_1005Metric"
			(at 221.615 195.58 0)
			(effects
				(font
					(size 1.27 1.27)
					(thickness 0.15)
				)
				(justify left bottom)
				(hide yes)
			)
		)
		(property "Datasheet" "https://www.murata.com/products/productdetail?partno=GRM155R60J106ME15%23"
			(at 224.155 195.58 0)
			(effects
				(font
					(size 1.27 1.27)
					(thickness 0.15)
				)
				(justify left bottom)
				(hide yes)
			)
		)
		(property "Description" ""
			(at 208.915 215.9 0)
			(effects
				(font
					(size 1.27 1.27)
				)
			)
		)
		(property "MPN" "GRM155R60J106ME15D"
			(at 226.695 195.58 0)
			(effects
				(font
					(size 1.27 1.27)
					(thickness 0.15)
				)
				(justify left bottom)
				(hide yes)
			)
		)
		(property "Manufacturer" "Murata"
			(at 229.235 195.58 0)
			(effects
				(font
					(size 1.27 1.27)
					(thickness 0.15)
				)
				(justify left bottom)
				(hide yes)
			)
		)
		(property "License" "Apache-2.0"
			(at 231.775 195.58 0)
			(effects
				(font
					(size 1.27 1.27)
					(thickness 0.15)
				)
				(justify left bottom)
				(hide yes)
			)
		)
		(property "Author" "Antmicro"
			(at 234.315 195.58 0)
			(effects
				(font
					(size 1.27 1.27)
					(thickness 0.15)
				)
				(justify left bottom)
				(hide yes)
			)
		)
		(property "Val" "10u"
			(at 211.2391 215.0467 90)
			(effects
				(font
					(size 1.27 1.27)
					(thickness 0.15)
				)
				(justify right)
			)
		)
		(property "Voltage" "6.3V"
			(at 236.855 195.58 0)
			(effects
				(font
					(size 1.27 1.27)
				)
				(justify left bottom)
				(hide yes)
			)
		)
		(property "Dielectric" "X5R"
			(at 239.395 195.58 0)
			(effects
				(font
					(size 1.27 1.27)
				)
				(justify left bottom)
				(hide yes)
			)
		)
		(pin "1"
		)
		(pin "2"
		)
		(instances
			(project "sodimm-ddr5-tester"
				(path ""
					(reference "C126")
					(unit 1)
				)
			)
		)
	)
	(symbol
		(lib_id "antmicropower:GND")
		(at 208.915 217.805 0)
		(unit 1)
		(exclude_from_sim no)
		(in_bom yes)
		(on_board yes)
		(dnp no)
		(property "Reference" "#PWR0209"
			(at 208.915 224.155 0)
			(effects
				(font
					(size 1.27 1.27)
				)
				(hide yes)
			)
		)
		(property "Value" "GND"
			(at 207.01 222.25 0)
			(effects
				(font
					(size 1.27 1.27)
					(thickness 0.15)
				)
				(justify left bottom)
			)
		)
		(property "Footprint" ""
			(at 217.805 225.425 0)
			(effects
				(font
					(size 1.27 1.27)
					(thickness 0.15)
				)
				(justify left bottom)
				(hide yes)
			)
		)
		(property "Datasheet" ""
			(at 217.805 230.505 0)
			(effects
				(font
					(size 1.27 1.27)
					(thickness 0.15)
				)
				(justify left bottom)
				(hide yes)
			)
		)
		(property "Description" ""
			(at 217.805 233.045 0)
			(effects
				(font
					(size 1.27 1.27)
				)
				(justify left bottom)
				(hide yes)
			)
		)
		(property "Author" "Antmicro"
			(at 217.805 225.425 0)
			(effects
				(font
					(size 1.27 1.27)
					(thickness 0.15)
				)
				(justify left bottom)
				(hide yes)
			)
		)
		(property "License" "Apache-2.0"
			(at 217.805 227.965 0)
			(effects
				(font
					(size 1.27 1.27)
					(thickness 0.15)
				)
				(justify left bottom)
				(hide yes)
			)
		)
		(pin "1"
		)
		(instances
			(project "sodimm-ddr5-tester"
				(path ""
					(reference "#PWR0209")
					(unit 1)
				)
			)
		)
	)
	(symbol
		(lib_id "antmicropower:GND")
		(at 269.24 223.52 0)
		(mirror y)
		(unit 1)
		(exclude_from_sim no)
		(in_bom yes)
		(on_board yes)
		(dnp no)
		(fields_autoplaced yes)
		(property "Reference" "#PWR0226"
			(at 269.24 229.87 0)
			(effects
				(font
					(size 1.27 1.27)
				)
				(hide yes)
			)
		)
		(property "Value" "GND"
			(at 271.78 224.79 0)
			(effects
				(font
					(size 1.27 1.27)
					(thickness 0.15)
				)
				(justify right)
			)
		)
		(property "Footprint" ""
			(at 260.35 231.14 0)
			(effects
				(font
					(size 1.27 1.27)
					(thickness 0.15)
				)
				(justify left bottom)
				(hide yes)
			)
		)
		(property "Datasheet" ""
			(at 260.35 236.22 0)
			(effects
				(font
					(size 1.27 1.27)
					(thickness 0.15)
				)
				(justify left bottom)
				(hide yes)
			)
		)
		(property "Description" ""
			(at 260.35 238.76 0)
			(effects
				(font
					(size 1.27 1.27)
				)
				(justify left bottom)
				(hide yes)
			)
		)
		(property "Author" "Antmicro"
			(at 260.35 231.14 0)
			(effects
				(font
					(size 1.27 1.27)
					(thickness 0.15)
				)
				(justify left bottom)
				(hide yes)
			)
		)
		(property "License" "Apache-2.0"
			(at 260.35 233.68 0)
			(effects
				(font
					(size 1.27 1.27)
					(thickness 0.15)
				)
				(justify left bottom)
				(hide yes)
			)
		)
		(pin "1"
		)
		(instances
			(project "sodimm-ddr5-tester"
				(path ""
					(reference "#PWR0226")
					(unit 1)
				)
			)
		)
	)
	(symbol
		(lib_id "antmicroResistors0402:R_20k_0402")
		(at 213.995 36.195 270)
		(unit 1)
		(exclude_from_sim no)
		(in_bom yes)
		(on_board yes)
		(dnp no)
		(property "Reference" "R85"
			(at 213.995 35.56 90)
			(effects
				(font
					(size 1.27 1.27)
				)
				(justify left)
			)
		)
		(property "Value" "R_20k_0402"
			(at 201.295 56.515 0)
			(effects
				(font
					(size 1.27 1.27)
					(thickness 0.15)
				)
				(justify left bottom)
				(hide yes)
			)
		)
		(property "Footprint" "antmicro-footprints:R_0402_1005Metric"
			(at 198.755 56.515 0)
			(effects
				(font
					(size 1.27 1.27)
					(thickness 0.15)
				)
				(justify left bottom)
				(hide yes)
			)
		)
		(property "Datasheet" "https://www.bourns.com/docs/product-datasheets/cr.pdf"
			(at 196.215 56.515 0)
			(effects
				(font
					(size 1.27 1.27)
					(thickness 0.15)
				)
				(justify left bottom)
				(hide yes)
			)
		)
		(property "Description" ""
			(at 213.995 36.195 0)
			(effects
				(font
					(size 1.27 1.27)
				)
			)
		)
		(property "Manufacturer" "Bourns"
			(at 191.135 56.515 0)
			(effects
				(font
					(size 1.27 1.27)
					(thickness 0.15)
				)
				(justify left bottom)
				(hide yes)
			)
		)
		(property "MPN" "CR0402-FX-2002GLF"
			(at 193.675 56.515 0)
			(effects
				(font
					(size 1.27 1.27)
					(thickness 0.15)
				)
				(justify left bottom)
				(hide yes)
			)
		)
		(property "Val" "20k"
			(at 213.995 41.91 90)
			(effects
				(font
					(size 1.27 1.27)
					(thickness 0.15)
				)
				(justify left)
			)
		)
		(property "License" "Apache-2.0"
			(at 188.595 56.515 0)
			(effects
				(font
					(size 1.27 1.27)
					(thickness 0.15)
				)
				(justify left bottom)
				(hide yes)
			)
		)
		(property "Author" "Antmicro"
			(at 186.055 56.515 0)
			(effects
				(font
					(size 1.27 1.27)
					(thickness 0.15)
				)
				(justify left bottom)
				(hide yes)
			)
		)
		(property "Tolerance" "1%"
			(at 203.835 56.515 0)
			(effects
				(font
					(size 1.27 1.27)
				)
				(justify left bottom)
				(hide yes)
			)
		)
		(pin "1"
		)
		(pin "2"
		)
		(instances
			(project "sodimm-ddr5-tester"
				(path ""
					(reference "R85")
					(unit 1)
				)
			)
		)
	)
	(symbol
		(lib_id "antmicropower:GND")
		(at 277.495 74.295 0)
		(mirror y)
		(unit 1)
		(exclude_from_sim no)
		(in_bom yes)
		(on_board yes)
		(dnp no)
		(fields_autoplaced yes)
		(property "Reference" "#PWR0233"
			(at 277.495 80.645 0)
			(effects
				(font
					(size 1.27 1.27)
				)
				(hide yes)
			)
		)
		(property "Value" "GND"
			(at 279.4 75.565 0)
			(effects
				(font
					(size 1.27 1.27)
					(thickness 0.15)
				)
				(justify right)
			)
		)
		(property "Footprint" ""
			(at 268.605 81.915 0)
			(effects
				(font
					(size 1.27 1.27)
					(thickness 0.15)
				)
				(justify left bottom)
				(hide yes)
			)
		)
		(property "Datasheet" ""
			(at 268.605 86.995 0)
			(effects
				(font
					(size 1.27 1.27)
					(thickness 0.15)
				)
				(justify left bottom)
				(hide yes)
			)
		)
		(property "Description" ""
			(at 268.605 89.535 0)
			(effects
				(font
					(size 1.27 1.27)
				)
				(justify left bottom)
				(hide yes)
			)
		)
		(property "Author" "Antmicro"
			(at 268.605 81.915 0)
			(effects
				(font
					(size 1.27 1.27)
					(thickness 0.15)
				)
				(justify left bottom)
				(hide yes)
			)
		)
		(property "License" "Apache-2.0"
			(at 268.605 84.455 0)
			(effects
				(font
					(size 1.27 1.27)
					(thickness 0.15)
				)
				(justify left bottom)
				(hide yes)
			)
		)
		(pin "1"
		)
		(instances
			(project "sodimm-ddr5-tester"
				(path ""
					(reference "#PWR0233")
					(unit 1)
				)
			)
		)
	)
	(symbol
		(lib_id "antmicropower:PWR_FLAG")
		(at 189.23 207.01 0)
		(unit 1)
		(exclude_from_sim no)
		(in_bom yes)
		(on_board yes)
		(dnp no)
		(property "Reference" "#FLG02"
			(at 189.23 205.105 0)
			(effects
				(font
					(size 1.27 1.27)
				)
				(hide yes)
			)
		)
		(property "Value" "PWR_FLAG"
			(at 188.722 203.2 0)
			(effects
				(font
					(size 1.27 1.27)
				)
			)
		)
		(property "Footprint" ""
			(at 189.23 207.01 0)
			(effects
				(font
					(size 1.27 1.27)
				)
				(hide yes)
			)
		)
		(property "Datasheet" ""
			(at 189.23 207.01 0)
			(effects
				(font
					(size 1.27 1.27)
				)
				(hide yes)
			)
		)
		(property "Description" ""
			(at 189.23 207.01 0)
			(effects
				(font
					(size 1.27 1.27)
				)
			)
		)
		(pin "1"
		)
		(instances
			(project "sodimm-ddr5-tester"
				(path ""
					(reference "#FLG02")
					(unit 1)
				)
			)
		)
	)
	(symbol
		(lib_id "antmicropower:GND")
		(at 195.58 266.7 0)
		(unit 1)
		(exclude_from_sim no)
		(in_bom yes)
		(on_board yes)
		(dnp no)
		(property "Reference" "#PWR0220"
			(at 195.58 273.05 0)
			(effects
				(font
					(size 1.27 1.27)
				)
				(hide yes)
			)
		)
		(property "Value" "GND"
			(at 193.675 271.145 0)
			(effects
				(font
					(size 1.27 1.27)
					(thickness 0.15)
				)
				(justify left bottom)
			)
		)
		(property "Footprint" ""
			(at 204.47 274.32 0)
			(effects
				(font
					(size 1.27 1.27)
					(thickness 0.15)
				)
				(justify left bottom)
				(hide yes)
			)
		)
		(property "Datasheet" ""
			(at 204.47 279.4 0)
			(effects
				(font
					(size 1.27 1.27)
					(thickness 0.15)
				)
				(justify left bottom)
				(hide yes)
			)
		)
		(property "Description" ""
			(at 204.47 281.94 0)
			(effects
				(font
					(size 1.27 1.27)
				)
				(justify left bottom)
				(hide yes)
			)
		)
		(property "Author" "Antmicro"
			(at 204.47 274.32 0)
			(effects
				(font
					(size 1.27 1.27)
					(thickness 0.15)
				)
				(justify left bottom)
				(hide yes)
			)
		)
		(property "License" "Apache-2.0"
			(at 204.47 276.86 0)
			(effects
				(font
					(size 1.27 1.27)
					(thickness 0.15)
				)
				(justify left bottom)
				(hide yes)
			)
		)
		(pin "1"
		)
		(instances
			(project "sodimm-ddr5-tester"
				(path ""
					(reference "#PWR0220")
					(unit 1)
				)
			)
		)
	)
	(symbol
		(lib_id "antmicropower:+5V")
		(at 167.64 201.93 0)
		(unit 1)
		(exclude_from_sim no)
		(in_bom yes)
		(on_board yes)
		(dnp no)
		(fields_autoplaced yes)
		(property "Reference" "#PWR0202"
			(at 167.64 205.74 0)
			(effects
				(font
					(size 1.27 1.27)
				)
				(hide yes)
			)
		)
		(property "Value" "+5V"
			(at 167.64 198.3556 0)
			(effects
				(font
					(size 1.27 1.27)
					(thickness 0.15)
				)
			)
		)
		(property "Footprint" ""
			(at 182.88 209.55 0)
			(effects
				(font
					(size 1.27 1.27)
					(thickness 0.15)
				)
				(justify left bottom)
				(hide yes)
			)
		)
		(property "Datasheet" ""
			(at 182.88 212.09 0)
			(effects
				(font
					(size 1.27 1.27)
					(thickness 0.15)
				)
				(justify left bottom)
				(hide yes)
			)
		)
		(property "Description" ""
			(at 167.64 201.93 0)
			(effects
				(font
					(size 1.27 1.27)
				)
			)
		)
		(property "Author" "Antmicro"
			(at 182.88 209.55 0)
			(effects
				(font
					(size 1.27 1.27)
					(thickness 0.15)
				)
				(justify left bottom)
				(hide yes)
			)
		)
		(property "License" "Apache-2.0"
			(at 182.88 212.09 0)
			(effects
				(font
					(size 1.27 1.27)
					(thickness 0.15)
				)
				(justify left bottom)
				(hide yes)
			)
		)
		(pin "1"
		)
		(instances
			(project "sodimm-ddr5-tester"
				(path ""
					(reference "#PWR0202")
					(unit 1)
				)
			)
		)
	)
	(symbol
		(lib_id "antmicroResistors0402:R_20k_0402")
		(at 194.945 36.195 270)
		(unit 1)
		(exclude_from_sim no)
		(in_bom yes)
		(on_board yes)
		(dnp no)
		(property "Reference" "R81"
			(at 194.945 35.56 90)
			(effects
				(font
					(size 1.27 1.27)
				)
				(justify left)
			)
		)
		(property "Value" "R_20k_0402"
			(at 182.245 56.515 0)
			(effects
				(font
					(size 1.27 1.27)
					(thickness 0.15)
				)
				(justify left bottom)
				(hide yes)
			)
		)
		(property "Footprint" "antmicro-footprints:R_0402_1005Metric"
			(at 179.705 56.515 0)
			(effects
				(font
					(size 1.27 1.27)
					(thickness 0.15)
				)
				(justify left bottom)
				(hide yes)
			)
		)
		(property "Datasheet" "https://www.bourns.com/docs/product-datasheets/cr.pdf"
			(at 177.165 56.515 0)
			(effects
				(font
					(size 1.27 1.27)
					(thickness 0.15)
				)
				(justify left bottom)
				(hide yes)
			)
		)
		(property "Description" ""
			(at 194.945 36.195 0)
			(effects
				(font
					(size 1.27 1.27)
				)
			)
		)
		(property "Manufacturer" "Bourns"
			(at 172.085 56.515 0)
			(effects
				(font
					(size 1.27 1.27)
					(thickness 0.15)
				)
				(justify left bottom)
				(hide yes)
			)
		)
		(property "MPN" "CR0402-FX-2002GLF"
			(at 174.625 56.515 0)
			(effects
				(font
					(size 1.27 1.27)
					(thickness 0.15)
				)
				(justify left bottom)
				(hide yes)
			)
		)
		(property "Val" "20k"
			(at 194.945 41.91 90)
			(effects
				(font
					(size 1.27 1.27)
					(thickness 0.15)
				)
				(justify left)
			)
		)
		(property "License" "Apache-2.0"
			(at 169.545 56.515 0)
			(effects
				(font
					(size 1.27 1.27)
					(thickness 0.15)
				)
				(justify left bottom)
				(hide yes)
			)
		)
		(property "Author" "Antmicro"
			(at 167.005 56.515 0)
			(effects
				(font
					(size 1.27 1.27)
					(thickness 0.15)
				)
				(justify left bottom)
				(hide yes)
			)
		)
		(property "Tolerance" "1%"
			(at 184.785 56.515 0)
			(effects
				(font
					(size 1.27 1.27)
				)
				(justify left bottom)
				(hide yes)
			)
		)
		(pin "1"
		)
		(pin "2"
		)
		(instances
			(project "sodimm-ddr5-tester"
				(path ""
					(reference "R81")
					(unit 1)
				)
			)
		)
	)
	(symbol
		(lib_id "antmicroTVSDiodes:TPD4E05U06QDQARQ1")
		(at 186.055 101.6 0)
		(unit 1)
		(exclude_from_sim no)
		(in_bom yes)
		(on_board yes)
		(dnp no)
		(property "Reference" "U12"
			(at 196.85 104.7749 0)
			(effects
				(font
					(size 1.27 1.27)
				)
				(justify left)
			)
		)
		(property "Value" "TPD4E05U06QDQARQ1"
			(at 187.96 114.935 0)
			(effects
				(font
					(size 1.27 1.27)
					(thickness 0.15)
				)
				(justify left)
			)
		)
		(property "Footprint" "antmicro-footprints:USON-10_2.5x1mm_P0.5mm"
			(at 210.185 106.68 0)
			(effects
				(font
					(size 1.27 1.27)
					(thickness 0.15)
				)
				(justify left bottom)
				(hide yes)
			)
		)
		(property "Datasheet" "https://www.ti.com/lit/ds/symlink/tpd4e05u06-q1.pdf?HQS=dis-mous-null-mousermode-dsf-pf-null-wwe&ts=1663591265741&ref_url=https%253A%252F%252Fwww.mouser.com%252F"
			(at 210.185 109.22 0)
			(effects
				(font
					(size 1.27 1.27)
					(thickness 0.15)
				)
				(justify left bottom)
				(hide yes)
			)
		)
		(property "Description" ""
			(at 186.055 101.6 0)
			(effects
				(font
					(size 1.27 1.27)
				)
			)
		)
		(property "Manufacturer" "Texas Instruments"
			(at 210.185 111.76 0)
			(effects
				(font
					(size 1.27 1.27)
					(thickness 0.15)
				)
				(justify left bottom)
				(hide yes)
			)
		)
		(property "MPN" "TPD4E05U06QDQARQ1"
			(at 210.185 114.3 0)
			(effects
				(font
					(size 1.27 1.27)
					(thickness 0.15)
				)
				(justify left bottom)
				(hide yes)
			)
		)
		(property "Author" "Antmicro"
			(at 210.185 116.84 0)
			(effects
				(font
					(size 1.27 1.27)
					(thickness 0.15)
				)
				(justify left bottom)
				(hide yes)
			)
		)
		(property "License" "Apache-2.0"
			(at 210.185 119.38 0)
			(effects
				(font
					(size 1.27 1.27)
					(thickness 0.15)
				)
				(justify left bottom)
				(hide yes)
			)
		)
		(pin "1"
		)
		(pin "10"
		)
		(pin "2"
		)
		(pin "3"
		)
		(pin "4"
		)
		(pin "5"
		)
		(pin "6"
		)
		(pin "7"
		)
		(pin "8"
		)
		(pin "9"
		)
		(instances
			(project "sodimm-ddr5-tester"
				(path ""
					(reference "U12")
					(unit 1)
				)
			)
		)
	)
	(symbol
		(lib_id "antmicroResistors0402:R_20k_0402")
		(at 207.645 36.195 270)
		(unit 1)
		(exclude_from_sim no)
		(in_bom yes)
		(on_board yes)
		(dnp no)
		(property "Reference" "R83"
			(at 207.645 35.56 90)
			(effects
				(font
					(size 1.27 1.27)
				)
				(justify left)
			)
		)
		(property "Value" "R_20k_0402"
			(at 194.945 56.515 0)
			(effects
				(font
					(size 1.27 1.27)
					(thickness 0.15)
				)
				(justify left bottom)
				(hide yes)
			)
		)
		(property "Footprint" "antmicro-footprints:R_0402_1005Metric"
			(at 192.405 56.515 0)
			(effects
				(font
					(size 1.27 1.27)
					(thickness 0.15)
				)
				(justify left bottom)
				(hide yes)
			)
		)
		(property "Datasheet" "https://www.bourns.com/docs/product-datasheets/cr.pdf"
			(at 189.865 56.515 0)
			(effects
				(font
					(size 1.27 1.27)
					(thickness 0.15)
				)
				(justify left bottom)
				(hide yes)
			)
		)
		(property "Description" ""
			(at 207.645 36.195 0)
			(effects
				(font
					(size 1.27 1.27)
				)
			)
		)
		(property "Manufacturer" "Bourns"
			(at 184.785 56.515 0)
			(effects
				(font
					(size 1.27 1.27)
					(thickness 0.15)
				)
				(justify left bottom)
				(hide yes)
			)
		)
		(property "MPN" "CR0402-FX-2002GLF"
			(at 187.325 56.515 0)
			(effects
				(font
					(size 1.27 1.27)
					(thickness 0.15)
				)
				(justify left bottom)
				(hide yes)
			)
		)
		(property "Val" "20k"
			(at 207.645 41.91 90)
			(effects
				(font
					(size 1.27 1.27)
					(thickness 0.15)
				)
				(justify left)
			)
		)
		(property "License" "Apache-2.0"
			(at 182.245 56.515 0)
			(effects
				(font
					(size 1.27 1.27)
					(thickness 0.15)
				)
				(justify left bottom)
				(hide yes)
			)
		)
		(property "Author" "Antmicro"
			(at 179.705 56.515 0)
			(effects
				(font
					(size 1.27 1.27)
					(thickness 0.15)
				)
				(justify left bottom)
				(hide yes)
			)
		)
		(property "Tolerance" "1%"
			(at 197.485 56.515 0)
			(effects
				(font
					(size 1.27 1.27)
				)
				(justify left bottom)
				(hide yes)
			)
		)
		(pin "1"
		)
		(pin "2"
		)
		(instances
			(project "sodimm-ddr5-tester"
				(path ""
					(reference "R83")
					(unit 1)
				)
			)
		)
	)
	(symbol
		(lib_id "antmicroResistors0402:R_20k_0402")
		(at 226.695 36.195 270)
		(unit 1)
		(exclude_from_sim no)
		(in_bom yes)
		(on_board yes)
		(dnp no)
		(property "Reference" "R87"
			(at 226.695 35.56 90)
			(effects
				(font
					(size 1.27 1.27)
				)
				(justify left)
			)
		)
		(property "Value" "R_20k_0402"
			(at 213.995 56.515 0)
			(effects
				(font
					(size 1.27 1.27)
					(thickness 0.15)
				)
				(justify left bottom)
				(hide yes)
			)
		)
		(property "Footprint" "antmicro-footprints:R_0402_1005Metric"
			(at 211.455 56.515 0)
			(effects
				(font
					(size 1.27 1.27)
					(thickness 0.15)
				)
				(justify left bottom)
				(hide yes)
			)
		)
		(property "Datasheet" "https://www.bourns.com/docs/product-datasheets/cr.pdf"
			(at 208.915 56.515 0)
			(effects
				(font
					(size 1.27 1.27)
					(thickness 0.15)
				)
				(justify left bottom)
				(hide yes)
			)
		)
		(property "Description" ""
			(at 226.695 36.195 0)
			(effects
				(font
					(size 1.27 1.27)
				)
			)
		)
		(property "Manufacturer" "Bourns"
			(at 203.835 56.515 0)
			(effects
				(font
					(size 1.27 1.27)
					(thickness 0.15)
				)
				(justify left bottom)
				(hide yes)
			)
		)
		(property "MPN" "CR0402-FX-2002GLF"
			(at 206.375 56.515 0)
			(effects
				(font
					(size 1.27 1.27)
					(thickness 0.15)
				)
				(justify left bottom)
				(hide yes)
			)
		)
		(property "Val" "20k"
			(at 226.695 41.91 90)
			(effects
				(font
					(size 1.27 1.27)
					(thickness 0.15)
				)
				(justify left)
			)
		)
		(property "License" "Apache-2.0"
			(at 201.295 56.515 0)
			(effects
				(font
					(size 1.27 1.27)
					(thickness 0.15)
				)
				(justify left bottom)
				(hide yes)
			)
		)
		(property "Author" "Antmicro"
			(at 198.755 56.515 0)
			(effects
				(font
					(size 1.27 1.27)
					(thickness 0.15)
				)
				(justify left bottom)
				(hide yes)
			)
		)
		(property "Tolerance" "1%"
			(at 216.535 56.515 0)
			(effects
				(font
					(size 1.27 1.27)
				)
				(justify left bottom)
				(hide yes)
			)
		)
		(pin "1"
		)
		(pin "2"
		)
		(instances
			(project "sodimm-ddr5-tester"
				(path ""
					(reference "R87")
					(unit 1)
				)
			)
		)
	)
	(symbol
		(lib_id "antmicroTestPoints:TP_1mm_SMD")
		(at 225.425 199.39 180)
		(unit 1)
		(exclude_from_sim no)
		(in_bom yes)
		(on_board yes)
		(dnp no)
		(fields_autoplaced yes)
		(property "Reference" "TP6"
			(at 220.8531 199.8238 0)
			(effects
				(font
					(size 1.27 1.27)
				)
				(justify left)
			)
		)
		(property "Value" "TP_1mm_SMD"
			(at 210.185 191.77 0)
			(effects
				(font
					(size 1.27 1.27)
					(thickness 0.15)
				)
				(justify left bottom)
				(hide yes)
			)
		)
		(property "Footprint" "antmicro-footprints:TP_SMD_1mm"
			(at 210.185 189.23 0)
			(effects
				(font
					(size 1.27 1.27)
					(thickness 0.15)
				)
				(justify left bottom)
				(hide yes)
			)
		)
		(property "Datasheet" ""
			(at 210.185 186.69 0)
			(effects
				(font
					(size 1.27 1.27)
					(thickness 0.15)
				)
				(justify left bottom)
				(hide yes)
			)
		)
		(property "Description" ""
			(at 225.425 199.39 0)
			(effects
				(font
					(size 1.27 1.27)
				)
			)
		)
		(property "MPN" ""
			(at 225.425 199.39 0)
			(effects
				(font
					(size 1.27 1.27)
				)
				(hide yes)
			)
		)
		(property "Manufacturer" ""
			(at 225.425 199.39 0)
			(effects
				(font
					(size 1.27 1.27)
				)
				(hide yes)
			)
		)
		(property "Author" "Antmicro"
			(at 210.185 184.15 0)
			(effects
				(font
					(size 1.27 1.27)
					(thickness 0.15)
				)
				(justify left bottom)
				(hide yes)
			)
		)
		(property "License" "Apache-2.0"
			(at 210.185 181.61 0)
			(effects
				(font
					(size 1.27 1.27)
					(thickness 0.15)
				)
				(justify left bottom)
				(hide yes)
			)
		)
		(pin "1"
		)
		(instances
			(project "sodimm-ddr5-tester"
				(path ""
					(reference "TP6")
					(unit 1)
				)
			)
		)
	)
	(symbol
		(lib_id "antmicroResistors0402:R_0R_0402")
		(at 193.04 158.75 0)
		(unit 1)
		(exclude_from_sim no)
		(in_bom yes)
		(on_board yes)
		(dnp no)
		(property "Reference" "R71"
			(at 198.12 157.48 0)
			(effects
				(font
					(size 1.27 1.27)
				)
				(justify left)
			)
		)
		(property "Value" "R_0R_0402"
			(at 213.36 171.45 0)
			(effects
				(font
					(size 1.27 1.27)
					(thickness 0.15)
				)
				(justify left bottom)
				(hide yes)
			)
		)
		(property "Footprint" "antmicro-footprints:R_0402_1005Metric"
			(at 213.36 173.99 0)
			(effects
				(font
					(size 1.27 1.27)
					(thickness 0.15)
				)
				(justify left bottom)
				(hide yes)
			)
		)
		(property "Datasheet" "https://industrial.panasonic.com/cdbs/www-data/pdf/RDA0000/AOA0000C301.pdf"
			(at 213.36 176.53 0)
			(effects
				(font
					(size 1.27 1.27)
					(thickness 0.15)
				)
				(justify left bottom)
				(hide yes)
			)
		)
		(property "Description" ""
			(at 193.04 158.75 0)
			(effects
				(font
					(size 1.27 1.27)
				)
			)
		)
		(property "Manufacturer" "Panasonic"
			(at 213.36 181.61 0)
			(effects
				(font
					(size 1.27 1.27)
					(thickness 0.15)
				)
				(justify left bottom)
				(hide yes)
			)
		)
		(property "MPN" "ERJ2GE0R00X"
			(at 213.36 179.07 0)
			(effects
				(font
					(size 1.27 1.27)
					(thickness 0.15)
				)
				(justify left bottom)
				(hide yes)
			)
		)
		(property "Val" "0R"
			(at 190.5 157.48 0)
			(effects
				(font
					(size 1.27 1.27)
					(thickness 0.15)
				)
				(justify left)
			)
		)
		(property "License" "Apache-2.0"
			(at 213.36 184.15 0)
			(effects
				(font
					(size 1.27 1.27)
					(thickness 0.15)
				)
				(justify left bottom)
				(hide yes)
			)
		)
		(property "Author" "Antmicro"
			(at 213.36 186.69 0)
			(effects
				(font
					(size 1.27 1.27)
					(thickness 0.15)
				)
				(justify left bottom)
				(hide yes)
			)
		)
		(property "Tolerance" "~"
			(at 213.36 168.91 0)
			(effects
				(font
					(size 1.27 1.27)
				)
				(justify left bottom)
				(hide yes)
			)
		)
		(property "Current" "1A"
			(at 213.36 189.23 0)
			(effects
				(font
					(size 1.27 1.27)
					(thickness 0.15)
				)
				(justify left bottom)
				(hide yes)
			)
		)
		(pin "1"
		)
		(pin "2"
		)
		(instances
			(project "sodimm-ddr5-tester"
				(path ""
					(reference "R71")
					(unit 1)
				)
			)
		)
	)
	(symbol
		(lib_id "antmicroDiodesRectifiersSingle:BAT54-02V-G3-08")
		(at 198.12 207.01 0)
		(mirror y)
		(unit 1)
		(exclude_from_sim no)
		(in_bom yes)
		(on_board yes)
		(dnp no)
		(property "Reference" "D14"
			(at 195.58 204.47 0)
			(effects
				(font
					(size 1.27 1.27)
					(thickness 0.15)
				)
			)
		)
		(property "Value" "BAT54-02V-G3-08"
			(at 176.53 222.25 0)
			(effects
				(font
					(size 1.27 1.27)
					(thickness 0.15)
				)
				(justify left bottom)
				(hide yes)
			)
		)
		(property "Footprint" "antmicro-footprints:SOD-523"
			(at 176.53 217.17 0)
			(effects
				(font
					(size 1.27 1.27)
					(thickness 0.15)
				)
				(justify left bottom)
				(hide yes)
			)
		)
		(property "Datasheet" "https://www.vishay.com/docs/85633/bat5402v.pdf"
			(at 176.53 219.71 0)
			(effects
				(font
					(size 1.27 1.27)
					(thickness 0.15)
				)
				(justify left bottom)
				(hide yes)
			)
		)
		(property "Description" "Small Signal Schottky Diode, Single, 30 V, 200 mA, 800 mV, 600 mA, 125 °C"
			(at 176.53 232.41 0)
			(effects
				(font
					(size 1.27 1.27)
				)
				(justify left bottom)
				(hide yes)
			)
		)
		(property "MPN" "BAT54-02V-G3-08"
			(at 195.834 210.058 0)
			(effects
				(font
					(size 1.27 1.27)
					(thickness 0.15)
				)
			)
		)
		(property "Manufacturer" "Vishay"
			(at 176.53 224.79 0)
			(effects
				(font
					(size 1.27 1.27)
					(thickness 0.15)
				)
				(justify left bottom)
				(hide yes)
			)
		)
		(property "Author" "Antmicro"
			(at 176.53 227.33 0)
			(effects
				(font
					(size 1.27 1.27)
					(thickness 0.15)
				)
				(justify left bottom)
				(hide yes)
			)
		)
		(property "License" "Apache-2.0"
			(at 176.53 229.87 0)
			(effects
				(font
					(size 1.27 1.27)
					(thickness 0.15)
				)
				(justify left bottom)
				(hide yes)
			)
		)
		(pin "2"
		)
		(pin "1"
		)
		(instances
			(project ""
				(path ""
					(reference "D14")
					(unit 1)
				)
			)
		)
	)
	(symbol
		(lib_id "antmicroResistors0402:R_330R_0402")
		(at 210.185 66.04 0)
		(unit 1)
		(exclude_from_sim no)
		(in_bom yes)
		(on_board yes)
		(dnp no)
		(property "Reference" "R84"
			(at 212.725 69.215 0)
			(effects
				(font
					(size 1.27 1.27)
				)
			)
		)
		(property "Value" "R_330R_0402"
			(at 230.505 78.74 0)
			(effects
				(font
					(size 1.27 1.27)
					(thickness 0.15)
				)
				(justify left bottom)
				(hide yes)
			)
		)
		(property "Footprint" "antmicro-footprints:R_0402_1005Metric"
			(at 230.505 81.28 0)
			(effects
				(font
					(size 1.27 1.27)
					(thickness 0.15)
				)
				(justify left bottom)
				(hide yes)
			)
		)
		(property "Datasheet" "https://www.bourns.com/docs/product-datasheets/cr.pdf"
			(at 230.505 83.82 0)
			(effects
				(font
					(size 1.27 1.27)
					(thickness 0.15)
				)
				(justify left bottom)
				(hide yes)
			)
		)
		(property "Description" ""
			(at 210.185 66.04 0)
			(effects
				(font
					(size 1.27 1.27)
				)
			)
		)
		(property "Manufacturer" "Bourns"
			(at 230.505 88.9 0)
			(effects
				(font
					(size 1.27 1.27)
					(thickness 0.15)
				)
				(justify left bottom)
				(hide yes)
			)
		)
		(property "MPN" "CR0402-FX-3300GLF"
			(at 230.505 86.36 0)
			(effects
				(font
					(size 1.27 1.27)
					(thickness 0.15)
				)
				(justify left bottom)
				(hide yes)
			)
		)
		(property "Val" "330R"
			(at 212.725 71.755 0)
			(effects
				(font
					(size 1.27 1.27)
					(thickness 0.15)
				)
			)
		)
		(property "License" "Apache-2.0"
			(at 230.505 91.44 0)
			(effects
				(font
					(size 1.27 1.27)
					(thickness 0.15)
				)
				(justify left bottom)
				(hide yes)
			)
		)
		(property "Author" "Antmicro"
			(at 230.505 93.98 0)
			(effects
				(font
					(size 1.27 1.27)
					(thickness 0.15)
				)
				(justify left bottom)
				(hide yes)
			)
		)
		(property "Tolerance" "1%"
			(at 230.505 76.2 0)
			(effects
				(font
					(size 1.27 1.27)
				)
				(justify left bottom)
				(hide yes)
			)
		)
		(pin "1"
		)
		(pin "2"
		)
		(instances
			(project "sodimm-ddr5-tester"
				(path ""
					(reference "R84")
					(unit 1)
				)
			)
		)
	)
	(symbol
		(lib_id "antmicropower:+3V3")
		(at 177.165 30.48 0)
		(unit 1)
		(exclude_from_sim no)
		(in_bom yes)
		(on_board yes)
		(dnp no)
		(property "Reference" "#PWR0216"
			(at 177.165 34.29 0)
			(effects
				(font
					(size 1.27 1.27)
				)
				(hide yes)
			)
		)
		(property "Value" "+3V3"
			(at 173.99 27.94 0)
			(effects
				(font
					(size 1.27 1.27)
					(thickness 0.15)
				)
				(justify left bottom)
			)
		)
		(property "Footprint" ""
			(at 192.405 38.1 0)
			(effects
				(font
					(size 1.27 1.27)
					(thickness 0.15)
				)
				(justify left bottom)
				(hide yes)
			)
		)
		(property "Datasheet" ""
			(at 192.405 40.64 0)
			(effects
				(font
					(size 1.27 1.27)
					(thickness 0.15)
				)
				(justify left bottom)
				(hide yes)
			)
		)
		(property "Description" ""
			(at 177.165 30.48 0)
			(effects
				(font
					(size 1.27 1.27)
				)
			)
		)
		(property "Author" "Antmicro"
			(at 192.405 33.02 0)
			(effects
				(font
					(size 1.27 1.27)
					(thickness 0.15)
				)
				(justify left bottom)
				(hide yes)
			)
		)
		(property "License" "Apache-2.0"
			(at 192.405 35.56 0)
			(effects
				(font
					(size 1.27 1.27)
					(thickness 0.15)
				)
				(justify left bottom)
				(hide yes)
			)
		)
		(pin "1"
		)
		(instances
			(project "sodimm-ddr5-tester"
				(path ""
					(reference "#PWR0216")
					(unit 1)
				)
			)
		)
	)
	(symbol
		(lib_id "antmicroTVSDiodes:TPD4E05U06QDQARQ1")
		(at 186.055 78.74 0)
		(unit 1)
		(exclude_from_sim no)
		(in_bom yes)
		(on_board yes)
		(dnp no)
		(property "Reference" "U14"
			(at 196.85 81.9149 0)
			(effects
				(font
					(size 1.27 1.27)
				)
				(justify left)
			)
		)
		(property "Value" "TPD4E05U06QDQARQ1"
			(at 187.96 92.075 0)
			(effects
				(font
					(size 1.27 1.27)
					(thickness 0.15)
				)
				(justify left)
			)
		)
		(property "Footprint" "antmicro-footprints:USON-10_2.5x1mm_P0.5mm"
			(at 210.185 83.82 0)
			(effects
				(font
					(size 1.27 1.27)
					(thickness 0.15)
				)
				(justify left bottom)
				(hide yes)
			)
		)
		(property "Datasheet" "https://www.ti.com/lit/ds/symlink/tpd4e05u06-q1.pdf?HQS=dis-mous-null-mousermode-dsf-pf-null-wwe&ts=1663591265741&ref_url=https%253A%252F%252Fwww.mouser.com%252F"
			(at 210.185 86.36 0)
			(effects
				(font
					(size 1.27 1.27)
					(thickness 0.15)
				)
				(justify left bottom)
				(hide yes)
			)
		)
		(property "Description" ""
			(at 186.055 78.74 0)
			(effects
				(font
					(size 1.27 1.27)
				)
			)
		)
		(property "Manufacturer" "Texas Instruments"
			(at 210.185 88.9 0)
			(effects
				(font
					(size 1.27 1.27)
					(thickness 0.15)
				)
				(justify left bottom)
				(hide yes)
			)
		)
		(property "MPN" "TPD4E05U06QDQARQ1"
			(at 210.185 91.44 0)
			(effects
				(font
					(size 1.27 1.27)
					(thickness 0.15)
				)
				(justify left bottom)
				(hide yes)
			)
		)
		(property "Author" "Antmicro"
			(at 210.185 93.98 0)
			(effects
				(font
					(size 1.27 1.27)
					(thickness 0.15)
				)
				(justify left bottom)
				(hide yes)
			)
		)
		(property "License" "Apache-2.0"
			(at 210.185 96.52 0)
			(effects
				(font
					(size 1.27 1.27)
					(thickness 0.15)
				)
				(justify left bottom)
				(hide yes)
			)
		)
		(pin "1"
		)
		(pin "10"
		)
		(pin "2"
		)
		(pin "3"
		)
		(pin "4"
		)
		(pin "5"
		)
		(pin "6"
		)
		(pin "7"
		)
		(pin "8"
		)
		(pin "9"
		)
		(instances
			(project "sodimm-ddr5-tester"
				(path ""
					(reference "U14")
					(unit 1)
				)
			)
		)
	)
	(symbol
		(lib_id "antmicroMemoryConnectorsPCCardSockets:MicroSD_693071020811")
		(at 234.95 45.72 0)
		(unit 1)
		(exclude_from_sim no)
		(in_bom yes)
		(on_board yes)
		(dnp no)
		(fields_autoplaced yes)
		(property "Reference" "J5"
			(at 257.175 36.195 0)
			(effects
				(font
					(size 1.27 1.27)
					(thickness 0.15)
				)
			)
		)
		(property "Value" "MicroSD_693071020811"
			(at 257.175 38.735 0)
			(effects
				(font
					(size 1.27 1.27)
					(thickness 0.15)
				)
			)
		)
		(property "Footprint" "antmicro-footprints:MicroSD_Wurth_693071020811"
			(at 290.83 53.34 0)
			(effects
				(font
					(size 1.27 1.27)
					(thickness 0.15)
				)
				(justify left bottom)
				(hide yes)
			)
		)
		(property "Datasheet" "https://www.we-online.com/catalog/datasheet/693071020811.pdf"
			(at 290.83 55.88 0)
			(effects
				(font
					(size 1.27 1.27)
					(thickness 0.15)
				)
				(justify left bottom)
				(hide yes)
			)
		)
		(property "Description" ""
			(at 234.95 45.72 0)
			(effects
				(font
					(size 1.27 1.27)
				)
			)
		)
		(property "Manufacturer" "Würth Elektronik"
			(at 290.83 58.42 0)
			(effects
				(font
					(size 1.27 1.27)
					(thickness 0.15)
				)
				(justify left bottom)
				(hide yes)
			)
		)
		(property "MPN" "693071020811"
			(at 290.83 60.96 0)
			(effects
				(font
					(size 1.27 1.27)
					(thickness 0.15)
				)
				(justify left bottom)
				(hide yes)
			)
		)
		(property "Author" "Antmicro"
			(at 290.83 63.5 0)
			(effects
				(font
					(size 1.27 1.27)
					(thickness 0.15)
				)
				(justify left bottom)
				(hide yes)
			)
		)
		(property "License" "Apache-2.0"
			(at 290.83 66.04 0)
			(effects
				(font
					(size 1.27 1.27)
					(thickness 0.15)
				)
				(justify left bottom)
				(hide yes)
			)
		)
		(pin "1"
		)
		(pin "2"
		)
		(pin "3"
		)
		(pin "4"
		)
		(pin "5"
		)
		(pin "6"
		)
		(pin "7"
		)
		(pin "8"
		)
		(pin "9"
		)
		(pin "SH"
		)
		(instances
			(project "sodimm-ddr5-tester"
				(path ""
					(reference "J5")
					(unit 1)
				)
			)
		)
	)
	(symbol
		(lib_id "antmicropower:+3V3")
		(at 188.595 29.845 0)
		(unit 1)
		(exclude_from_sim no)
		(in_bom yes)
		(on_board yes)
		(dnp no)
		(property "Reference" "#PWR0218"
			(at 188.595 33.655 0)
			(effects
				(font
					(size 1.27 1.27)
				)
				(hide yes)
			)
		)
		(property "Value" "+3V3"
			(at 185.42 27.305 0)
			(effects
				(font
					(size 1.27 1.27)
					(thickness 0.15)
				)
				(justify left bottom)
			)
		)
		(property "Footprint" ""
			(at 203.835 37.465 0)
			(effects
				(font
					(size 1.27 1.27)
					(thickness 0.15)
				)
				(justify left bottom)
				(hide yes)
			)
		)
		(property "Datasheet" ""
			(at 203.835 40.005 0)
			(effects
				(font
					(size 1.27 1.27)
					(thickness 0.15)
				)
				(justify left bottom)
				(hide yes)
			)
		)
		(property "Description" ""
			(at 188.595 29.845 0)
			(effects
				(font
					(size 1.27 1.27)
				)
			)
		)
		(property "Author" "Antmicro"
			(at 203.835 32.385 0)
			(effects
				(font
					(size 1.27 1.27)
					(thickness 0.15)
				)
				(justify left bottom)
				(hide yes)
			)
		)
		(property "License" "Apache-2.0"
			(at 203.835 34.925 0)
			(effects
				(font
					(size 1.27 1.27)
					(thickness 0.15)
				)
				(justify left bottom)
				(hide yes)
			)
		)
		(pin "1"
		)
		(instances
			(project "sodimm-ddr5-tester"
				(path ""
					(reference "#PWR0218")
					(unit 1)
				)
			)
		)
	)
	(symbol
		(lib_id "antmicroTVSDiodes:TPD4E05U06QDQARQ1")
		(at 196.85 231.775 0)
		(unit 1)
		(exclude_from_sim no)
		(in_bom yes)
		(on_board yes)
		(dnp no)
		(property "Reference" "U10"
			(at 207.645 234.9499 0)
			(effects
				(font
					(size 1.27 1.27)
				)
				(justify left)
			)
		)
		(property "Value" "TPD4E05U06QDQARQ1"
			(at 199.39 245.11 0)
			(effects
				(font
					(size 1.27 1.27)
					(thickness 0.15)
				)
				(justify left)
			)
		)
		(property "Footprint" "antmicro-footprints:USON-10_2.5x1mm_P0.5mm"
			(at 220.98 236.855 0)
			(effects
				(font
					(size 1.27 1.27)
					(thickness 0.15)
				)
				(justify left bottom)
				(hide yes)
			)
		)
		(property "Datasheet" "https://www.ti.com/lit/ds/symlink/tpd4e05u06-q1.pdf?HQS=dis-mous-null-mousermode-dsf-pf-null-wwe&ts=1663591265741&ref_url=https%253A%252F%252Fwww.mouser.com%252F"
			(at 220.98 239.395 0)
			(effects
				(font
					(size 1.27 1.27)
					(thickness 0.15)
				)
				(justify left bottom)
				(hide yes)
			)
		)
		(property "Description" ""
			(at 196.85 231.775 0)
			(effects
				(font
					(size 1.27 1.27)
				)
			)
		)
		(property "Manufacturer" "Texas Instruments"
			(at 220.98 241.935 0)
			(effects
				(font
					(size 1.27 1.27)
					(thickness 0.15)
				)
				(justify left bottom)
				(hide yes)
			)
		)
		(property "MPN" "TPD4E05U06QDQARQ1"
			(at 220.98 244.475 0)
			(effects
				(font
					(size 1.27 1.27)
					(thickness 0.15)
				)
				(justify left bottom)
				(hide yes)
			)
		)
		(property "Author" "Antmicro"
			(at 220.98 247.015 0)
			(effects
				(font
					(size 1.27 1.27)
					(thickness 0.15)
				)
				(justify left bottom)
				(hide yes)
			)
		)
		(property "License" "Apache-2.0"
			(at 220.98 249.555 0)
			(effects
				(font
					(size 1.27 1.27)
					(thickness 0.15)
				)
				(justify left bottom)
				(hide yes)
			)
		)
		(pin "1"
		)
		(pin "10"
		)
		(pin "2"
		)
		(pin "3"
		)
		(pin "4"
		)
		(pin "5"
		)
		(pin "6"
		)
		(pin "7"
		)
		(pin "8"
		)
		(pin "9"
		)
		(instances
			(project "sodimm-ddr5-tester"
				(path ""
					(reference "U10")
					(unit 1)
				)
			)
		)
	)
	(symbol
		(lib_id "antmicroTestPoints:TP_1mm_SMD")
		(at 225.425 194.31 180)
		(unit 1)
		(exclude_from_sim no)
		(in_bom yes)
		(on_board yes)
		(dnp no)
		(fields_autoplaced yes)
		(property "Reference" "TP5"
			(at 220.8531 194.7438 0)
			(effects
				(font
					(size 1.27 1.27)
				)
				(justify left)
			)
		)
		(property "Value" "TP_1mm_SMD"
			(at 210.185 186.69 0)
			(effects
				(font
					(size 1.27 1.27)
					(thickness 0.15)
				)
				(justify left bottom)
				(hide yes)
			)
		)
		(property "Footprint" "antmicro-footprints:TP_SMD_1mm"
			(at 210.185 184.15 0)
			(effects
				(font
					(size 1.27 1.27)
					(thickness 0.15)
				)
				(justify left bottom)
				(hide yes)
			)
		)
		(property "Datasheet" ""
			(at 210.185 181.61 0)
			(effects
				(font
					(size 1.27 1.27)
					(thickness 0.15)
				)
				(justify left bottom)
				(hide yes)
			)
		)
		(property "Description" ""
			(at 225.425 194.31 0)
			(effects
				(font
					(size 1.27 1.27)
				)
			)
		)
		(property "MPN" ""
			(at 225.425 194.31 0)
			(effects
				(font
					(size 1.27 1.27)
				)
				(hide yes)
			)
		)
		(property "Manufacturer" ""
			(at 225.425 194.31 0)
			(effects
				(font
					(size 1.27 1.27)
				)
				(hide yes)
			)
		)
		(property "Author" "Antmicro"
			(at 210.185 179.07 0)
			(effects
				(font
					(size 1.27 1.27)
					(thickness 0.15)
				)
				(justify left bottom)
				(hide yes)
			)
		)
		(property "License" "Apache-2.0"
			(at 210.185 176.53 0)
			(effects
				(font
					(size 1.27 1.27)
					(thickness 0.15)
				)
				(justify left bottom)
				(hide yes)
			)
		)
		(pin "1"
		)
		(instances
			(project "sodimm-ddr5-tester"
				(path ""
					(reference "TP5")
					(unit 1)
				)
			)
		)
	)
	(symbol
		(lib_id "antmicropower:PWR_FLAG")
		(at 208.915 205.74 0)
		(unit 1)
		(exclude_from_sim no)
		(in_bom yes)
		(on_board yes)
		(dnp no)
		(fields_autoplaced yes)
		(property "Reference" "#FLG03"
			(at 208.915 203.835 0)
			(effects
				(font
					(size 1.27 1.27)
				)
				(hide yes)
			)
		)
		(property "Value" "PWR_FLAG"
			(at 208.915 202.1642 0)
			(effects
				(font
					(size 1.27 1.27)
				)
			)
		)
		(property "Footprint" ""
			(at 208.915 205.74 0)
			(effects
				(font
					(size 1.27 1.27)
				)
				(hide yes)
			)
		)
		(property "Datasheet" ""
			(at 208.915 205.74 0)
			(effects
				(font
					(size 1.27 1.27)
				)
				(hide yes)
			)
		)
		(property "Description" ""
			(at 208.915 205.74 0)
			(effects
				(font
					(size 1.27 1.27)
				)
			)
		)
		(pin "1"
		)
		(instances
			(project "sodimm-ddr5-tester"
				(path ""
					(reference "#FLG03")
					(unit 1)
				)
			)
		)
	)
	(symbol
		(lib_id "antmicropower:GND")
		(at 184.785 90.17 0)
		(unit 1)
		(exclude_from_sim no)
		(in_bom yes)
		(on_board yes)
		(dnp no)
		(property "Reference" "#PWR0228"
			(at 184.785 96.52 0)
			(effects
				(font
					(size 1.27 1.27)
				)
				(hide yes)
			)
		)
		(property "Value" "GND"
			(at 182.88 94.615 0)
			(effects
				(font
					(size 1.27 1.27)
					(thickness 0.15)
				)
				(justify left bottom)
			)
		)
		(property "Footprint" ""
			(at 193.675 97.79 0)
			(effects
				(font
					(size 1.27 1.27)
					(thickness 0.15)
				)
				(justify left bottom)
				(hide yes)
			)
		)
		(property "Datasheet" ""
			(at 193.675 102.87 0)
			(effects
				(font
					(size 1.27 1.27)
					(thickness 0.15)
				)
				(justify left bottom)
				(hide yes)
			)
		)
		(property "Description" ""
			(at 193.675 105.41 0)
			(effects
				(font
					(size 1.27 1.27)
				)
				(justify left bottom)
				(hide yes)
			)
		)
		(property "Author" "Antmicro"
			(at 193.675 97.79 0)
			(effects
				(font
					(size 1.27 1.27)
					(thickness 0.15)
				)
				(justify left bottom)
				(hide yes)
			)
		)
		(property "License" "Apache-2.0"
			(at 193.675 100.33 0)
			(effects
				(font
					(size 1.27 1.27)
					(thickness 0.15)
				)
				(justify left bottom)
				(hide yes)
			)
		)
		(pin "1"
		)
		(instances
			(project "sodimm-ddr5-tester"
				(path ""
					(reference "#PWR0228")
					(unit 1)
				)
			)
		)
	)
	(symbol
		(lib_id "antmicroResistors0402:R_330R_0402")
		(at 266.065 212.09 0)
		(mirror y)
		(unit 1)
		(exclude_from_sim no)
		(in_bom yes)
		(on_board yes)
		(dnp no)
		(property "Reference" "R89"
			(at 263.525 207.01 0)
			(effects
				(font
					(size 1.27 1.27)
				)
			)
		)
		(property "Value" "R_330R_0402"
			(at 245.745 224.79 0)
			(effects
				(font
					(size 1.27 1.27)
					(thickness 0.15)
				)
				(justify left bottom)
				(hide yes)
			)
		)
		(property "Footprint" "antmicro-footprints:R_0402_1005Metric"
			(at 245.745 227.33 0)
			(effects
				(font
					(size 1.27 1.27)
					(thickness 0.15)
				)
				(justify left bottom)
				(hide yes)
			)
		)
		(property "Datasheet" "https://www.bourns.com/docs/product-datasheets/cr.pdf"
			(at 245.745 229.87 0)
			(effects
				(font
					(size 1.27 1.27)
					(thickness 0.15)
				)
				(justify left bottom)
				(hide yes)
			)
		)
		(property "Description" ""
			(at 266.065 212.09 0)
			(effects
				(font
					(size 1.27 1.27)
				)
			)
		)
		(property "Manufacturer" "Bourns"
			(at 245.745 234.95 0)
			(effects
				(font
					(size 1.27 1.27)
					(thickness 0.15)
				)
				(justify left bottom)
				(hide yes)
			)
		)
		(property "MPN" "CR0402-FX-3300GLF"
			(at 245.745 232.41 0)
			(effects
				(font
					(size 1.27 1.27)
					(thickness 0.15)
				)
				(justify left bottom)
				(hide yes)
			)
		)
		(property "Val" "330R"
			(at 263.525 209.55 0)
			(effects
				(font
					(size 1.27 1.27)
					(thickness 0.15)
				)
			)
		)
		(property "License" "Apache-2.0"
			(at 245.745 237.49 0)
			(effects
				(font
					(size 1.27 1.27)
					(thickness 0.15)
				)
				(justify left bottom)
				(hide yes)
			)
		)
		(property "Author" "Antmicro"
			(at 245.745 240.03 0)
			(effects
				(font
					(size 1.27 1.27)
					(thickness 0.15)
				)
				(justify left bottom)
				(hide yes)
			)
		)
		(property "Tolerance" "1%"
			(at 245.745 222.25 0)
			(effects
				(font
					(size 1.27 1.27)
				)
				(justify left bottom)
				(hide yes)
			)
		)
		(pin "1"
		)
		(pin "2"
		)
		(instances
			(project "sodimm-ddr5-tester"
				(path ""
					(reference "R89")
					(unit 1)
				)
			)
		)
	)
	(symbol
		(lib_id "antmicroCapacitors0402:C_100n_0402")
		(at 260.985 220.98 0)
		(mirror x)
		(unit 1)
		(exclude_from_sim no)
		(in_bom yes)
		(on_board yes)
		(dnp no)
		(property "Reference" "C132"
			(at 263.5186 215.265 0)
			(effects
				(font
					(size 1.27 1.27)
				)
			)
		)
		(property "Value" "C_100n_0402"
			(at 281.305 210.82 0)
			(effects
				(font
					(size 1.27 1.27)
					(thickness 0.15)
				)
				(justify left bottom)
				(hide yes)
			)
		)
		(property "Footprint" "antmicro-footprints:C_0402_1005Metric"
			(at 281.305 208.28 0)
			(effects
				(font
					(size 1.27 1.27)
					(thickness 0.15)
				)
				(justify left bottom)
				(hide yes)
			)
		)
		(property "Datasheet" "https://www.murata.com/products/productdetail?partno=GRM155R61H104KE14%23"
			(at 281.305 205.74 0)
			(effects
				(font
					(size 1.27 1.27)
					(thickness 0.15)
				)
				(justify left bottom)
				(hide yes)
			)
		)
		(property "Description" ""
			(at 260.985 220.98 0)
			(effects
				(font
					(size 1.27 1.27)
				)
			)
		)
		(property "Manufacturer" "Murata"
			(at 281.305 200.66 0)
			(effects
				(font
					(size 1.27 1.27)
					(thickness 0.15)
				)
				(justify left bottom)
				(hide yes)
			)
		)
		(property "MPN" "GRM155R61H104KE14D"
			(at 281.305 203.2 0)
			(effects
				(font
					(size 1.27 1.27)
					(thickness 0.15)
				)
				(justify left bottom)
				(hide yes)
			)
		)
		(property "Val" "100n"
			(at 263.525 217.805 0)
			(effects
				(font
					(size 1.27 1.27)
					(thickness 0.15)
				)
			)
		)
		(property "License" "Apache-2.0"
			(at 281.305 198.12 0)
			(effects
				(font
					(size 1.27 1.27)
					(thickness 0.15)
				)
				(justify left bottom)
				(hide yes)
			)
		)
		(property "Author" "Antmicro"
			(at 281.305 195.58 0)
			(effects
				(font
					(size 1.27 1.27)
					(thickness 0.15)
				)
				(justify left bottom)
				(hide yes)
			)
		)
		(property "Voltage" "50V"
			(at 281.305 193.04 0)
			(effects
				(font
					(size 1.27 1.27)
				)
				(justify left bottom)
				(hide yes)
			)
		)
		(property "Dielectric" "X5R"
			(at 281.305 190.5 0)
			(effects
				(font
					(size 1.27 1.27)
				)
				(justify left bottom)
				(hide yes)
			)
		)
		(pin "1"
		)
		(pin "2"
		)
		(instances
			(project "sodimm-ddr5-tester"
				(path ""
					(reference "C132")
					(unit 1)
				)
			)
		)
	)
	(symbol
		(lib_id "antmicroTestPoints:TP_1mm_SMD")
		(at 225.425 186.69 180)
		(unit 1)
		(exclude_from_sim no)
		(in_bom yes)
		(on_board yes)
		(dnp no)
		(fields_autoplaced yes)
		(property "Reference" "TP3"
			(at 220.8531 187.1238 0)
			(effects
				(font
					(size 1.27 1.27)
				)
				(justify left)
			)
		)
		(property "Value" "TP_1mm_SMD"
			(at 210.185 179.07 0)
			(effects
				(font
					(size 1.27 1.27)
					(thickness 0.15)
				)
				(justify left bottom)
				(hide yes)
			)
		)
		(property "Footprint" "antmicro-footprints:TP_SMD_1mm"
			(at 210.185 176.53 0)
			(effects
				(font
					(size 1.27 1.27)
					(thickness 0.15)
				)
				(justify left bottom)
				(hide yes)
			)
		)
		(property "Datasheet" ""
			(at 210.185 173.99 0)
			(effects
				(font
					(size 1.27 1.27)
					(thickness 0.15)
				)
				(justify left bottom)
				(hide yes)
			)
		)
		(property "Description" ""
			(at 225.425 186.69 0)
			(effects
				(font
					(size 1.27 1.27)
				)
			)
		)
		(property "MPN" ""
			(at 225.425 186.69 0)
			(effects
				(font
					(size 1.27 1.27)
				)
				(hide yes)
			)
		)
		(property "Manufacturer" ""
			(at 225.425 186.69 0)
			(effects
				(font
					(size 1.27 1.27)
				)
				(hide yes)
			)
		)
		(property "Author" "Antmicro"
			(at 210.185 171.45 0)
			(effects
				(font
					(size 1.27 1.27)
					(thickness 0.15)
				)
				(justify left bottom)
				(hide yes)
			)
		)
		(property "License" "Apache-2.0"
			(at 210.185 168.91 0)
			(effects
				(font
					(size 1.27 1.27)
					(thickness 0.15)
				)
				(justify left bottom)
				(hide yes)
			)
		)
		(pin "1"
		)
		(instances
			(project "sodimm-ddr5-tester"
				(path ""
					(reference "TP3")
					(unit 1)
				)
			)
		)
	)
	(symbol
		(lib_id "antmicroFerriteBeadsandChips:FB_120Z_2A_Murata-BLM18PG_0603")
		(at 170.18 207.01 0)
		(unit 1)
		(exclude_from_sim no)
		(in_bom yes)
		(on_board yes)
		(dnp no)
		(fields_autoplaced yes)
		(property "Reference" "FB3"
			(at 172.6819 201.615 0)
			(effects
				(font
					(size 1.27 1.27)
					(thickness 0.15)
				)
			)
		)
		(property "Value" "FB_120Z_2A_Murata-BLM18PG_0603"
			(at 185.42 209.55 0)
			(effects
				(font
					(size 1.27 1.27)
					(thickness 0.15)
				)
				(justify left bottom)
				(hide yes)
			)
		)
		(property "Footprint" "antmicro-footprints:FB_0603_1608Metric"
			(at 185.42 214.63 0)
			(effects
				(font
					(size 1.27 1.27)
					(thickness 0.15)
				)
				(justify left bottom)
				(hide yes)
			)
		)
		(property "Datasheet" "https://www.murata.com/en-us/products/productdata/8796738650142/ENFA0003.pdf"
			(at 185.42 217.17 0)
			(effects
				(font
					(size 1.27 1.27)
					(thickness 0.15)
				)
				(justify left bottom)
				(hide yes)
			)
		)
		(property "Description" ""
			(at 170.18 207.01 0)
			(effects
				(font
					(size 1.27 1.27)
				)
			)
		)
		(property "Val" "120Z/2A"
			(at 172.6819 204.1453 0)
			(effects
				(font
					(size 1.27 1.27)
				)
			)
		)
		(property "MPN" "BLM18PG121SN1D"
			(at 185.42 219.71 0)
			(effects
				(font
					(size 1.27 1.27)
					(thickness 0.15)
				)
				(justify left bottom)
				(hide yes)
			)
		)
		(property "Manufacturer" "Murata"
			(at 185.42 222.25 0)
			(effects
				(font
					(size 1.27 1.27)
					(thickness 0.15)
				)
				(justify left bottom)
				(hide yes)
			)
		)
		(property "Author" "Antmicro"
			(at 185.42 224.79 0)
			(effects
				(font
					(size 1.27 1.27)
					(thickness 0.15)
				)
				(justify left bottom)
				(hide yes)
			)
		)
		(property "License" "Apache-2.0"
			(at 185.42 227.33 0)
			(effects
				(font
					(size 1.27 1.27)
					(thickness 0.15)
				)
				(justify left bottom)
				(hide yes)
			)
		)
		(pin "1"
		)
		(pin "2"
		)
		(instances
			(project "sodimm-ddr5-tester"
				(path ""
					(reference "FB3")
					(unit 1)
				)
			)
		)
	)
	(symbol
		(lib_id "antmicroTestPoints:TP_1mm_SMD")
		(at 225.425 189.23 180)
		(unit 1)
		(exclude_from_sim no)
		(in_bom yes)
		(on_board yes)
		(dnp no)
		(fields_autoplaced yes)
		(property "Reference" "TP4"
			(at 220.8531 189.6638 0)
			(effects
				(font
					(size 1.27 1.27)
				)
				(justify left)
			)
		)
		(property "Value" "TP_1mm_SMD"
			(at 210.185 181.61 0)
			(effects
				(font
					(size 1.27 1.27)
					(thickness 0.15)
				)
				(justify left bottom)
				(hide yes)
			)
		)
		(property "Footprint" "antmicro-footprints:TP_SMD_1mm"
			(at 210.185 179.07 0)
			(effects
				(font
					(size 1.27 1.27)
					(thickness 0.15)
				)
				(justify left bottom)
				(hide yes)
			)
		)
		(property "Datasheet" ""
			(at 210.185 176.53 0)
			(effects
				(font
					(size 1.27 1.27)
					(thickness 0.15)
				)
				(justify left bottom)
				(hide yes)
			)
		)
		(property "Description" ""
			(at 225.425 189.23 0)
			(effects
				(font
					(size 1.27 1.27)
				)
			)
		)
		(property "MPN" ""
			(at 225.425 189.23 0)
			(effects
				(font
					(size 1.27 1.27)
				)
				(hide yes)
			)
		)
		(property "Manufacturer" ""
			(at 225.425 189.23 0)
			(effects
				(font
					(size 1.27 1.27)
				)
				(hide yes)
			)
		)
		(property "Author" "Antmicro"
			(at 210.185 173.99 0)
			(effects
				(font
					(size 1.27 1.27)
					(thickness 0.15)
				)
				(justify left bottom)
				(hide yes)
			)
		)
		(property "License" "Apache-2.0"
			(at 210.185 171.45 0)
			(effects
				(font
					(size 1.27 1.27)
					(thickness 0.15)
				)
				(justify left bottom)
				(hide yes)
			)
		)
		(pin "1"
		)
		(instances
			(project "sodimm-ddr5-tester"
				(path ""
					(reference "TP4")
					(unit 1)
				)
			)
		)
	)
	(symbol
		(lib_id "antmicroResistors0402:R_0R_0402")
		(at 193.04 173.99 0)
		(unit 1)
		(exclude_from_sim no)
		(in_bom yes)
		(on_board yes)
		(dnp no)
		(property "Reference" "R75"
			(at 198.12 172.72 0)
			(effects
				(font
					(size 1.27 1.27)
				)
				(justify left)
			)
		)
		(property "Value" "R_0R_0402"
			(at 213.36 186.69 0)
			(effects
				(font
					(size 1.27 1.27)
					(thickness 0.15)
				)
				(justify left bottom)
				(hide yes)
			)
		)
		(property "Footprint" "antmicro-footprints:R_0402_1005Metric"
			(at 213.36 189.23 0)
			(effects
				(font
					(size 1.27 1.27)
					(thickness 0.15)
				)
				(justify left bottom)
				(hide yes)
			)
		)
		(property "Datasheet" "https://industrial.panasonic.com/cdbs/www-data/pdf/RDA0000/AOA0000C301.pdf"
			(at 213.36 191.77 0)
			(effects
				(font
					(size 1.27 1.27)
					(thickness 0.15)
				)
				(justify left bottom)
				(hide yes)
			)
		)
		(property "Description" ""
			(at 193.04 173.99 0)
			(effects
				(font
					(size 1.27 1.27)
				)
			)
		)
		(property "Manufacturer" "Panasonic"
			(at 213.36 196.85 0)
			(effects
				(font
					(size 1.27 1.27)
					(thickness 0.15)
				)
				(justify left bottom)
				(hide yes)
			)
		)
		(property "MPN" "ERJ2GE0R00X"
			(at 213.36 194.31 0)
			(effects
				(font
					(size 1.27 1.27)
					(thickness 0.15)
				)
				(justify left bottom)
				(hide yes)
			)
		)
		(property "Val" "0R"
			(at 190.5 172.72 0)
			(effects
				(font
					(size 1.27 1.27)
					(thickness 0.15)
				)
				(justify left)
			)
		)
		(property "License" "Apache-2.0"
			(at 213.36 199.39 0)
			(effects
				(font
					(size 1.27 1.27)
					(thickness 0.15)
				)
				(justify left bottom)
				(hide yes)
			)
		)
		(property "Author" "Antmicro"
			(at 213.36 201.93 0)
			(effects
				(font
					(size 1.27 1.27)
					(thickness 0.15)
				)
				(justify left bottom)
				(hide yes)
			)
		)
		(property "Tolerance" "~"
			(at 213.36 184.15 0)
			(effects
				(font
					(size 1.27 1.27)
				)
				(justify left bottom)
				(hide yes)
			)
		)
		(property "Current" "1A"
			(at 213.36 204.47 0)
			(effects
				(font
					(size 1.27 1.27)
					(thickness 0.15)
				)
				(justify left bottom)
				(hide yes)
			)
		)
		(pin "1"
		)
		(pin "2"
		)
		(instances
			(project "sodimm-ddr5-tester"
				(path ""
					(reference "R75")
					(unit 1)
				)
			)
		)
	)
	(symbol
		(lib_id "antmicroResistors0402:R_0R_0402")
		(at 193.04 156.21 0)
		(unit 1)
		(exclude_from_sim no)
		(in_bom yes)
		(on_board yes)
		(dnp no)
		(property "Reference" "R70"
			(at 198.12 154.94 0)
			(effects
				(font
					(size 1.27 1.27)
				)
				(justify left)
			)
		)
		(property "Value" "R_0R_0402"
			(at 213.36 168.91 0)
			(effects
				(font
					(size 1.27 1.27)
					(thickness 0.15)
				)
				(justify left bottom)
				(hide yes)
			)
		)
		(property "Footprint" "antmicro-footprints:R_0402_1005Metric"
			(at 213.36 171.45 0)
			(effects
				(font
					(size 1.27 1.27)
					(thickness 0.15)
				)
				(justify left bottom)
				(hide yes)
			)
		)
		(property "Datasheet" "https://industrial.panasonic.com/cdbs/www-data/pdf/RDA0000/AOA0000C301.pdf"
			(at 213.36 173.99 0)
			(effects
				(font
					(size 1.27 1.27)
					(thickness 0.15)
				)
				(justify left bottom)
				(hide yes)
			)
		)
		(property "Description" ""
			(at 193.04 156.21 0)
			(effects
				(font
					(size 1.27 1.27)
				)
			)
		)
		(property "Manufacturer" "Panasonic"
			(at 213.36 179.07 0)
			(effects
				(font
					(size 1.27 1.27)
					(thickness 0.15)
				)
				(justify left bottom)
				(hide yes)
			)
		)
		(property "MPN" "ERJ2GE0R00X"
			(at 213.36 176.53 0)
			(effects
				(font
					(size 1.27 1.27)
					(thickness 0.15)
				)
				(justify left bottom)
				(hide yes)
			)
		)
		(property "Val" "0R"
			(at 190.5 154.94 0)
			(effects
				(font
					(size 1.27 1.27)
					(thickness 0.15)
				)
				(justify left)
			)
		)
		(property "License" "Apache-2.0"
			(at 213.36 181.61 0)
			(effects
				(font
					(size 1.27 1.27)
					(thickness 0.15)
				)
				(justify left bottom)
				(hide yes)
			)
		)
		(property "Author" "Antmicro"
			(at 213.36 184.15 0)
			(effects
				(font
					(size 1.27 1.27)
					(thickness 0.15)
				)
				(justify left bottom)
				(hide yes)
			)
		)
		(property "Tolerance" "~"
			(at 213.36 166.37 0)
			(effects
				(font
					(size 1.27 1.27)
				)
				(justify left bottom)
				(hide yes)
			)
		)
		(property "Current" "1A"
			(at 213.36 186.69 0)
			(effects
				(font
					(size 1.27 1.27)
					(thickness 0.15)
				)
				(justify left bottom)
				(hide yes)
			)
		)
		(pin "1"
		)
		(pin "2"
		)
		(instances
			(project "sodimm-ddr5-tester"
				(path ""
					(reference "R70")
					(unit 1)
				)
			)
		)
	)
	(symbol
		(lib_id "antmicropower:GND")
		(at 184.785 113.03 0)
		(unit 1)
		(exclude_from_sim no)
		(in_bom yes)
		(on_board yes)
		(dnp no)
		(property "Reference" "#PWR0221"
			(at 184.785 119.38 0)
			(effects
				(font
					(size 1.27 1.27)
				)
				(hide yes)
			)
		)
		(property "Value" "GND"
			(at 182.88 117.475 0)
			(effects
				(font
					(size 1.27 1.27)
					(thickness 0.15)
				)
				(justify left bottom)
			)
		)
		(property "Footprint" ""
			(at 193.675 120.65 0)
			(effects
				(font
					(size 1.27 1.27)
					(thickness 0.15)
				)
				(justify left bottom)
				(hide yes)
			)
		)
		(property "Datasheet" ""
			(at 193.675 125.73 0)
			(effects
				(font
					(size 1.27 1.27)
					(thickness 0.15)
				)
				(justify left bottom)
				(hide yes)
			)
		)
		(property "Description" ""
			(at 193.675 128.27 0)
			(effects
				(font
					(size 1.27 1.27)
				)
				(justify left bottom)
				(hide yes)
			)
		)
		(property "Author" "Antmicro"
			(at 193.675 120.65 0)
			(effects
				(font
					(size 1.27 1.27)
					(thickness 0.15)
				)
				(justify left bottom)
				(hide yes)
			)
		)
		(property "License" "Apache-2.0"
			(at 193.675 123.19 0)
			(effects
				(font
					(size 1.27 1.27)
					(thickness 0.15)
				)
				(justify left bottom)
				(hide yes)
			)
		)
		(pin "1"
		)
		(instances
			(project "sodimm-ddr5-tester"
				(path ""
					(reference "#PWR0221")
					(unit 1)
				)
			)
		)
	)
)
